G04 ================== begin FILE IDENTIFICATION RECORD ==================*
G04 Layout Name:  12004-1.brd*
G04 Film Name:    L8*
G04 File Format:  Gerber RS274X*
G04 File Origin:  Cadence Allegro 16.2-S033*
G04 Origin Date:  Tue Oct 16 14:36:11 2012*
G04 *
G04 Layer:  VIA CLASS/BOTTOM*
G04 Layer:  PIN/BOTTOM*
G04 Layer:  ETCH/BOTTOM*
G04 Layer:  DRAWING FORMAT/LAYER_PCB_STORY*
G04 Layer:  DRAWING FORMAT/LAYER_L8*
G04 *
G04 Offset:    (0.00 0.00)*
G04 Mirror:    No*
G04 Mode:      Positive*
G04 Rotation:  0*
G04 FullContactRelief:  No*
G04 UndefLineWidth:     6.00*
G04 ================== end FILE IDENTIFICATION RECORD ====================*
%FSLAX35Y35*MOIN*%
%IR0*IPPOS*OFA0.00000B0.00000*MIA0B0*SFA1.00000B1.00000*%
%AMMACRO22*
4,1,40,.011,.007,
.011,-.007,
.010939,-.007695,
.010759,-.008368,
.010464,-.009,
.010064,-.009571,
.009571,-.010064,
.009,-.010464,
.008368,-.010759,
.007695,-.010939,
.007,-.011,
-.007,-.011,
-.007695,-.010939,
-.008368,-.010759,
-.009,-.010464,
-.009571,-.010064,
-.010064,-.009571,
-.010464,-.009,
-.010759,-.008368,
-.010939,-.007695,
-.011,-.007,
-.011,.007,
-.010939,.007695,
-.010759,.008368,
-.010464,.009,
-.010064,.009571,
-.009571,.010064,
-.009,.010464,
-.008368,.010759,
-.007695,.010939,
-.007,.011,
.007,.011,
.007695,.010939,
.008368,.010759,
.009,.010464,
.009571,.010064,
.010064,.009571,
.010464,.009,
.010759,.008368,
.010939,.007695,
.011,.007,
0.0*
%
%ADD22MACRO22*%
%AMMACRO43*
4,1,40,-.017,-.013,
-.017,.013,
-.016939,.013695,
-.016759,.014368,
-.016464,.015,
-.016064,.015571,
-.015571,.016064,
-.015,.016464,
-.014368,.016759,
-.013695,.016939,
-.013,.017,
.013,.017,
.013695,.016939,
.014368,.016759,
.015,.016464,
.015571,.016064,
.016064,.015571,
.016464,.015,
.016759,.014368,
.016939,.013695,
.017,.013,
.017,-.013,
.016939,-.013695,
.016759,-.014368,
.016464,-.015,
.016064,-.015571,
.015571,-.016064,
.015,-.016464,
.014368,-.016759,
.013695,-.016939,
.013,-.017,
-.013,-.017,
-.013695,-.016939,
-.014368,-.016759,
-.015,-.016464,
-.015571,-.016064,
-.016064,-.015571,
-.016464,-.015,
-.016759,-.014368,
-.016939,-.013695,
-.017,-.013,
0.0*
%
%ADD43MACRO43*%
%AMMACRO30*
4,1,40,.013,-.017,
-.013,-.017,
-.013695,-.016939,
-.014368,-.016759,
-.015,-.016464,
-.015571,-.016064,
-.016064,-.015571,
-.016464,-.015,
-.016759,-.014368,
-.016939,-.013695,
-.017,-.013,
-.017,.013,
-.016939,.013695,
-.016759,.014368,
-.016464,.015,
-.016064,.015571,
-.015571,.016064,
-.015,.016464,
-.014368,.016759,
-.013695,.016939,
-.013,.017,
.013,.017,
.013695,.016939,
.014368,.016759,
.015,.016464,
.015571,.016064,
.016064,.015571,
.016464,.015,
.016759,.014368,
.016939,.013695,
.017,.013,
.017,-.013,
.016939,-.013695,
.016759,-.014368,
.016464,-.015,
.016064,-.015571,
.015571,-.016064,
.015,-.016464,
.014368,-.016759,
.013695,-.016939,
.013,-.017,
0.0*
%
%ADD30MACRO30*%
%ADD10C,.01*%
%ADD14C,.02*%
%ADD62R,.085X.301*%
%ADD12C,.022*%
%ADD63R,.126X.028*%
%ADD35C,.032*%
%ADD16C,.05*%
%ADD54C,.061*%
%ADD64R,.165X.028*%
%ADD37C,.055*%
%ADD15C,.046*%
%ADD13C,.028*%
%ADD11R,.05X.05*%
%AMMACRO33*
4,1,40,.007,-.011,
-.007,-.011,
-.007695,-.010939,
-.008368,-.010759,
-.009,-.010464,
-.009571,-.010064,
-.010064,-.009571,
-.010464,-.009,
-.010759,-.008368,
-.010939,-.007695,
-.011,-.007,
-.011,.007,
-.010939,.007695,
-.010759,.008368,
-.010464,.009,
-.010064,.009571,
-.009571,.010064,
-.009,.010464,
-.008368,.010759,
-.007695,.010939,
-.007,.011,
.007,.011,
.007695,.010939,
.008368,.010759,
.009,.010464,
.009571,.010064,
.010064,.009571,
.010464,.009,
.010759,.008368,
.010939,.007695,
.011,.007,
.011,-.007,
.010939,-.007695,
.010759,-.008368,
.010464,-.009,
.010064,-.009571,
.009571,-.010064,
.009,-.010464,
.008368,-.010759,
.007695,-.010939,
.007,-.011,
0.0*
%
%ADD33MACRO33*%
%AMMACRO23*
4,1,40,-.011,-.007,
-.011,.007,
-.010939,.007695,
-.010759,.008368,
-.010464,.009,
-.010064,.009571,
-.009571,.010064,
-.009,.010464,
-.008368,.010759,
-.007695,.010939,
-.007,.011,
.007,.011,
.007695,.010939,
.008368,.010759,
.009,.010464,
.009571,.010064,
.010064,.009571,
.010464,.009,
.010759,.008368,
.010939,.007695,
.011,.007,
.011,-.007,
.010939,-.007695,
.010759,-.008368,
.010464,-.009,
.010064,-.009571,
.009571,-.010064,
.009,-.010464,
.008368,-.010759,
.007695,-.010939,
.007,-.011,
-.007,-.011,
-.007695,-.010939,
-.008368,-.010759,
-.009,-.010464,
-.009571,-.010064,
-.010064,-.009571,
-.010464,-.009,
-.010759,-.008368,
-.010939,-.007695,
-.011,-.007,
0.0*
%
%ADD23MACRO23*%
%AMMACRO48*
4,1,40,-.012,-.008,
-.012,.008,
-.011939,.008695,
-.011759,.009368,
-.011464,.01,
-.011064,.010571,
-.010571,.011064,
-.01,.011464,
-.009368,.011759,
-.008695,.011939,
-.008,.012,
.008,.012,
.008695,.011939,
.009368,.011759,
.01,.011464,
.010571,.011064,
.011064,.010571,
.011464,.01,
.011759,.009368,
.011939,.008695,
.012,.008,
.012,-.008,
.011939,-.008695,
.011759,-.009368,
.011464,-.01,
.011064,-.010571,
.010571,-.011064,
.01,-.011464,
.009368,-.011759,
.008695,-.011939,
.008,-.012,
-.008,-.012,
-.008695,-.011939,
-.009368,-.011759,
-.01,-.011464,
-.010571,-.011064,
-.011064,-.010571,
-.011464,-.01,
-.011759,-.009368,
-.011939,-.008695,
-.012,-.008,
0.0*
%
%ADD48MACRO48*%
%AMMACRO32*
4,1,40,-.008,.012,
.008,.012,
.008695,.011939,
.009368,.011759,
.01,.011464,
.010571,.011064,
.011064,.010571,
.011464,.01,
.011759,.009368,
.011939,.008695,
.012,.008,
.012,-.008,
.011939,-.008695,
.011759,-.009368,
.011464,-.01,
.011064,-.010571,
.010571,-.011064,
.01,-.011464,
.009368,-.011759,
.008695,-.011939,
.008,-.012,
-.008,-.012,
-.008695,-.011939,
-.009368,-.011759,
-.01,-.011464,
-.010571,-.011064,
-.011064,-.010571,
-.011464,-.01,
-.011759,-.009368,
-.011939,-.008695,
-.012,-.008,
-.012,.008,
-.011939,.008695,
-.011759,.009368,
-.011464,.01,
-.011064,.010571,
-.010571,.011064,
-.01,.011464,
-.009368,.011759,
-.008695,.011939,
-.008,.012,
0.0*
%
%ADD32MACRO32*%
%AMMACRO44*
4,1,40,-.013,.017,
.013,.017,
.013695,.016939,
.014368,.016759,
.015,.016464,
.015571,.016064,
.016064,.015571,
.016464,.015,
.016759,.014368,
.016939,.013695,
.017,.013,
.017,-.013,
.016939,-.013695,
.016759,-.014368,
.016464,-.015,
.016064,-.015571,
.015571,-.016064,
.015,-.016464,
.014368,-.016759,
.013695,-.016939,
.013,-.017,
-.013,-.017,
-.013695,-.016939,
-.014368,-.016759,
-.015,-.016464,
-.015571,-.016064,
-.016064,-.015571,
-.016464,-.015,
-.016759,-.014368,
-.016939,-.013695,
-.017,-.013,
-.017,.013,
-.016939,.013695,
-.016759,.014368,
-.016464,.015,
-.016064,.015571,
-.015571,.016064,
-.015,.016464,
-.014368,.016759,
-.013695,.016939,
-.013,.017,
0.0*
%
%ADD44MACRO44*%
%AMMACRO50*
4,1,40,.017,.013,
.017,-.013,
.016939,-.013695,
.016759,-.014368,
.016464,-.015,
.016064,-.015571,
.015571,-.016064,
.015,-.016464,
.014368,-.016759,
.013695,-.016939,
.013,-.017,
-.013,-.017,
-.013695,-.016939,
-.014368,-.016759,
-.015,-.016464,
-.015571,-.016064,
-.016064,-.015571,
-.016464,-.015,
-.016759,-.014368,
-.016939,-.013695,
-.017,-.013,
-.017,.013,
-.016939,.013695,
-.016759,.014368,
-.016464,.015,
-.016064,.015571,
-.015571,.016064,
-.015,.016464,
-.014368,.016759,
-.013695,.016939,
-.013,.017,
.013,.017,
.013695,.016939,
.014368,.016759,
.015,.016464,
.015571,.016064,
.016064,.015571,
.016464,.015,
.016759,.014368,
.016939,.013695,
.017,.013,
0.0*
%
%ADD50MACRO50*%
%AMMACRO34*
4,1,40,.007,-.011,
-.007,-.011,
-.007695,-.010939,
-.008368,-.010759,
-.009,-.010464,
-.009571,-.010064,
-.010064,-.009571,
-.010464,-.009,
-.010759,-.008368,
-.010939,-.007695,
-.011,-.007,
-.011,.007,
-.010939,.007695,
-.010759,.008368,
-.010464,.009,
-.010064,.009571,
-.009571,.010064,
-.009,.010464,
-.008368,.010759,
-.007695,.010939,
-.007,.011,
.007,.011,
.007695,.010939,
.008368,.010759,
.009,.010464,
.009571,.010064,
.010064,.009571,
.010464,.009,
.010759,.008368,
.010939,.007695,
.011,.007,
.011,-.007,
.010939,-.007695,
.010759,-.008368,
.010464,-.009,
.010064,-.009571,
.009571,-.010064,
.009,-.010464,
.008368,-.010759,
.007695,-.010939,
.007,-.011,
0.0*
%
%ADD34MACRO34*%
%AMMACRO24*
4,1,40,-.011,-.007,
-.011,.007,
-.010939,.007695,
-.010759,.008368,
-.010464,.009,
-.010064,.009571,
-.009571,.010064,
-.009,.010464,
-.008368,.010759,
-.007695,.010939,
-.007,.011,
.007,.011,
.007695,.010939,
.008368,.010759,
.009,.010464,
.009571,.010064,
.010064,.009571,
.010464,.009,
.010759,.008368,
.010939,.007695,
.011,.007,
.011,-.007,
.010939,-.007695,
.010759,-.008368,
.010464,-.009,
.010064,-.009571,
.009571,-.010064,
.009,-.010464,
.008368,-.010759,
.007695,-.010939,
.007,-.011,
-.007,-.011,
-.007695,-.010939,
-.008368,-.010759,
-.009,-.010464,
-.009571,-.010064,
-.010064,-.009571,
-.010464,-.009,
-.010759,-.008368,
-.010939,-.007695,
-.011,-.007,
0.0*
%
%ADD24MACRO24*%
%AMMACRO47*
4,1,40,-.012,-.008,
-.012,.008,
-.011939,.008695,
-.011759,.009368,
-.011464,.01,
-.011064,.010571,
-.010571,.011064,
-.01,.011464,
-.009368,.011759,
-.008695,.011939,
-.008,.012,
.008,.012,
.008695,.011939,
.009368,.011759,
.01,.011464,
.010571,.011064,
.011064,.010571,
.011464,.01,
.011759,.009368,
.011939,.008695,
.012,.008,
.012,-.008,
.011939,-.008695,
.011759,-.009368,
.011464,-.01,
.011064,-.010571,
.010571,-.011064,
.01,-.011464,
.009368,-.011759,
.008695,-.011939,
.008,-.012,
-.008,-.012,
-.008695,-.011939,
-.009368,-.011759,
-.01,-.011464,
-.010571,-.011064,
-.011064,-.010571,
-.011464,-.01,
-.011759,-.009368,
-.011939,-.008695,
-.012,-.008,
0.0*
%
%ADD47MACRO47*%
%AMMACRO31*
4,1,40,-.008,.012,
.008,.012,
.008695,.011939,
.009368,.011759,
.01,.011464,
.010571,.011064,
.011064,.010571,
.011464,.01,
.011759,.009368,
.011939,.008695,
.012,.008,
.012,-.008,
.011939,-.008695,
.011759,-.009368,
.011464,-.01,
.011064,-.010571,
.010571,-.011064,
.01,-.011464,
.009368,-.011759,
.008695,-.011939,
.008,-.012,
-.008,-.012,
-.008695,-.011939,
-.009368,-.011759,
-.01,-.011464,
-.010571,-.011064,
-.011064,-.010571,
-.011464,-.01,
-.011759,-.009368,
-.011939,-.008695,
-.012,-.008,
-.012,.008,
-.011939,.008695,
-.011759,.009368,
-.011464,.01,
-.011064,.010571,
-.010571,.011064,
-.01,.011464,
-.009368,.011759,
-.008695,.011939,
-.008,.012,
0.0*
%
%ADD31MACRO31*%
%AMMACRO45*
4,1,40,-.013,.017,
.013,.017,
.013695,.016939,
.014368,.016759,
.015,.016464,
.015571,.016064,
.016064,.015571,
.016464,.015,
.016759,.014368,
.016939,.013695,
.017,.013,
.017,-.013,
.016939,-.013695,
.016759,-.014368,
.016464,-.015,
.016064,-.015571,
.015571,-.016064,
.015,-.016464,
.014368,-.016759,
.013695,-.016939,
.013,-.017,
-.013,-.017,
-.013695,-.016939,
-.014368,-.016759,
-.015,-.016464,
-.015571,-.016064,
-.016064,-.015571,
-.016464,-.015,
-.016759,-.014368,
-.016939,-.013695,
-.017,-.013,
-.017,.013,
-.016939,.013695,
-.016759,.014368,
-.016464,.015,
-.016064,.015571,
-.015571,.016064,
-.015,.016464,
-.014368,.016759,
-.013695,.016939,
-.013,.017,
0.0*
%
%ADD45MACRO45*%
%AMMACRO51*
4,1,40,.017,.013,
.017,-.013,
.016939,-.013695,
.016759,-.014368,
.016464,-.015,
.016064,-.015571,
.015571,-.016064,
.015,-.016464,
.014368,-.016759,
.013695,-.016939,
.013,-.017,
-.013,-.017,
-.013695,-.016939,
-.014368,-.016759,
-.015,-.016464,
-.015571,-.016064,
-.016064,-.015571,
-.016464,-.015,
-.016759,-.014368,
-.016939,-.013695,
-.017,-.013,
-.017,.013,
-.016939,.013695,
-.016759,.014368,
-.016464,.015,
-.016064,.015571,
-.015571,.016064,
-.015,.016464,
-.014368,.016759,
-.013695,.016939,
-.013,.017,
.013,.017,
.013695,.016939,
.014368,.016759,
.015,.016464,
.015571,.016064,
.016064,.015571,
.016464,.015,
.016759,.014368,
.016939,.013695,
.017,.013,
0.0*
%
%ADD51MACRO51*%
%ADD57R,.042X.014*%
%ADD56R,.014X.042*%
%ADD46R,.045X.03*%
%ADD28R,.03X.045*%
%ADD61R,.038X.012*%
%ADD60R,.012X.038*%
%ADD38R,.016X.06*%
%ADD17C,.213*%
%ADD27R,.065X.05*%
%ADD53R,.045X.055*%
%ADD49R,.014X.076*%
%ADD36R,.076X.014*%
%ADD58R,.081X.065*%
%ADD39R,.055X.045*%
%ADD59R,.065X.081*%
%ADD52C,.158*%
%ADD55R,.128X.128*%
%AMMACRO18*
4,1,40,-.02,-.006,
-.019878,-.007389,
-.019518,-.008736,
-.018928,-.01,
-.018128,-.011142,
-.017142,-.012128,
-.016,-.012928,
-.014736,-.013518,
-.013389,-.013878,
-.012,-.014,
.012,-.014,
.013389,-.013878,
.014736,-.013518,
.016,-.012928,
.017142,-.012128,
.018128,-.011142,
.018928,-.01,
.019518,-.008736,
.019878,-.007389,
.02,-.006,
.02,.006,
.019878,.007389,
.019518,.008736,
.018928,.01,
.018128,.011142,
.017142,.012128,
.016,.012928,
.014736,.013518,
.013389,.013878,
.012,.014,
-.012,.014,
-.013389,.013878,
-.014736,.013518,
-.016,.012928,
-.017142,.012128,
-.018128,.011142,
-.018928,.01,
-.019518,.008736,
-.019878,.007389,
-.02,.006,
-.02,-.006,
0.0*
%
%ADD18MACRO18*%
%AMMACRO41*
4,1,40,.012,.008,
.012,-.008,
.011939,-.008695,
.011759,-.009368,
.011464,-.01,
.011064,-.010571,
.010571,-.011064,
.01,-.011464,
.009368,-.011759,
.008695,-.011939,
.008,-.012,
-.008,-.012,
-.008695,-.011939,
-.009368,-.011759,
-.01,-.011464,
-.010571,-.011064,
-.011064,-.010571,
-.011464,-.01,
-.011759,-.009368,
-.011939,-.008695,
-.012,-.008,
-.012,.008,
-.011939,.008695,
-.011759,.009368,
-.011464,.01,
-.011064,.010571,
-.010571,.011064,
-.01,.011464,
-.009368,.011759,
-.008695,.011939,
-.008,.012,
.008,.012,
.008695,.011939,
.009368,.011759,
.01,.011464,
.010571,.011064,
.011064,.010571,
.011464,.01,
.011759,.009368,
.011939,.008695,
.012,.008,
0.0*
%
%ADD41MACRO41*%
%AMMACRO26*
4,1,40,-.007,.011,
.007,.011,
.007695,.010939,
.008368,.010759,
.009,.010464,
.009571,.010064,
.010064,.009571,
.010464,.009,
.010759,.008368,
.010939,.007695,
.011,.007,
.011,-.007,
.010939,-.007695,
.010759,-.008368,
.010464,-.009,
.010064,-.009571,
.009571,-.010064,
.009,-.010464,
.008368,-.010759,
.007695,-.010939,
.007,-.011,
-.007,-.011,
-.007695,-.010939,
-.008368,-.010759,
-.009,-.010464,
-.009571,-.010064,
-.010064,-.009571,
-.010464,-.009,
-.010759,-.008368,
-.010939,-.007695,
-.011,-.007,
-.011,.007,
-.010939,.007695,
-.010759,.008368,
-.010464,.009,
-.010064,.009571,
-.009571,.010064,
-.009,.010464,
-.008368,.010759,
-.007695,.010939,
-.007,.011,
0.0*
%
%ADD26MACRO26*%
%AMMACRO20*
4,1,40,.008,-.012,
-.008,-.012,
-.008695,-.011939,
-.009368,-.011759,
-.01,-.011464,
-.010571,-.011064,
-.011064,-.010571,
-.011464,-.01,
-.011759,-.009368,
-.011939,-.008695,
-.012,-.008,
-.012,.008,
-.011939,.008695,
-.011759,.009368,
-.011464,.01,
-.011064,.010571,
-.010571,.011064,
-.01,.011464,
-.009368,.011759,
-.008695,.011939,
-.008,.012,
.008,.012,
.008695,.011939,
.009368,.011759,
.01,.011464,
.010571,.011064,
.011064,.010571,
.011464,.01,
.011759,.009368,
.011939,.008695,
.012,.008,
.012,-.008,
.011939,-.008695,
.011759,-.009368,
.011464,-.01,
.011064,-.010571,
.010571,-.011064,
.01,-.011464,
.009368,-.011759,
.008695,-.011939,
.008,-.012,
0.0*
%
%ADD20MACRO20*%
%AMMACRO21*
4,1,40,.011,.007,
.011,-.007,
.010939,-.007695,
.010759,-.008368,
.010464,-.009,
.010064,-.009571,
.009571,-.010064,
.009,-.010464,
.008368,-.010759,
.007695,-.010939,
.007,-.011,
-.007,-.011,
-.007695,-.010939,
-.008368,-.010759,
-.009,-.010464,
-.009571,-.010064,
-.010064,-.009571,
-.010464,-.009,
-.010759,-.008368,
-.010939,-.007695,
-.011,-.007,
-.011,.007,
-.010939,.007695,
-.010759,.008368,
-.010464,.009,
-.010064,.009571,
-.009571,.010064,
-.009,.010464,
-.008368,.010759,
-.007695,.010939,
-.007,.011,
.007,.011,
.007695,.010939,
.008368,.010759,
.009,.010464,
.009571,.010064,
.010064,.009571,
.010464,.009,
.010759,.008368,
.010939,.007695,
.011,.007,
0.0*
%
%ADD21MACRO21*%
%AMMACRO42*
4,1,40,-.017,-.013,
-.017,.013,
-.016939,.013695,
-.016759,.014368,
-.016464,.015,
-.016064,.015571,
-.015571,.016064,
-.015,.016464,
-.014368,.016759,
-.013695,.016939,
-.013,.017,
.013,.017,
.013695,.016939,
.014368,.016759,
.015,.016464,
.015571,.016064,
.016064,.015571,
.016464,.015,
.016759,.014368,
.016939,.013695,
.017,.013,
.017,-.013,
.016939,-.013695,
.016759,-.014368,
.016464,-.015,
.016064,-.015571,
.015571,-.016064,
.015,-.016464,
.014368,-.016759,
.013695,-.016939,
.013,-.017,
-.013,-.017,
-.013695,-.016939,
-.014368,-.016759,
-.015,-.016464,
-.015571,-.016064,
-.016064,-.015571,
-.016464,-.015,
-.016759,-.014368,
-.016939,-.013695,
-.017,-.013,
0.0*
%
%ADD42MACRO42*%
%AMMACRO29*
4,1,40,.013,-.017,
-.013,-.017,
-.013695,-.016939,
-.014368,-.016759,
-.015,-.016464,
-.015571,-.016064,
-.016064,-.015571,
-.016464,-.015,
-.016759,-.014368,
-.016939,-.013695,
-.017,-.013,
-.017,.013,
-.016939,.013695,
-.016759,.014368,
-.016464,.015,
-.016064,.015571,
-.015571,.016064,
-.015,.016464,
-.014368,.016759,
-.013695,.016939,
-.013,.017,
.013,.017,
.013695,.016939,
.014368,.016759,
.015,.016464,
.015571,.016064,
.016064,.015571,
.016464,.015,
.016759,.014368,
.016939,.013695,
.017,.013,
.017,-.013,
.016939,-.013695,
.016759,-.014368,
.016464,-.015,
.016064,-.015571,
.015571,-.016064,
.015,-.016464,
.014368,-.016759,
.013695,-.016939,
.013,-.017,
0.0*
%
%ADD29MACRO29*%
%AMMACRO40*
4,1,40,.012,.008,
.012,-.008,
.011939,-.008695,
.011759,-.009368,
.011464,-.01,
.011064,-.010571,
.010571,-.011064,
.01,-.011464,
.009368,-.011759,
.008695,-.011939,
.008,-.012,
-.008,-.012,
-.008695,-.011939,
-.009368,-.011759,
-.01,-.011464,
-.010571,-.011064,
-.011064,-.010571,
-.011464,-.01,
-.011759,-.009368,
-.011939,-.008695,
-.012,-.008,
-.012,.008,
-.011939,.008695,
-.011759,.009368,
-.011464,.01,
-.011064,.010571,
-.010571,.011064,
-.01,.011464,
-.009368,.011759,
-.008695,.011939,
-.008,.012,
.008,.012,
.008695,.011939,
.009368,.011759,
.01,.011464,
.010571,.011064,
.011064,.010571,
.011464,.01,
.011759,.009368,
.011939,.008695,
.012,.008,
0.0*
%
%ADD40MACRO40*%
%AMMACRO25*
4,1,40,-.007,.011,
.007,.011,
.007695,.010939,
.008368,.010759,
.009,.010464,
.009571,.010064,
.010064,.009571,
.010464,.009,
.010759,.008368,
.010939,.007695,
.011,.007,
.011,-.007,
.010939,-.007695,
.010759,-.008368,
.010464,-.009,
.010064,-.009571,
.009571,-.010064,
.009,-.010464,
.008368,-.010759,
.007695,-.010939,
.007,-.011,
-.007,-.011,
-.007695,-.010939,
-.008368,-.010759,
-.009,-.010464,
-.009571,-.010064,
-.010064,-.009571,
-.010464,-.009,
-.010759,-.008368,
-.010939,-.007695,
-.011,-.007,
-.011,.007,
-.010939,.007695,
-.010759,.008368,
-.010464,.009,
-.010064,.009571,
-.009571,.010064,
-.009,.010464,
-.008368,.010759,
-.007695,.010939,
-.007,.011,
0.0*
%
%ADD25MACRO25*%
%AMMACRO19*
4,1,40,.008,-.012,
-.008,-.012,
-.008695,-.011939,
-.009368,-.011759,
-.01,-.011464,
-.010571,-.011064,
-.011064,-.010571,
-.011464,-.01,
-.011759,-.009368,
-.011939,-.008695,
-.012,-.008,
-.012,.008,
-.011939,.008695,
-.011759,.009368,
-.011464,.01,
-.011064,.010571,
-.010571,.011064,
-.01,.011464,
-.009368,.011759,
-.008695,.011939,
-.008,.012,
.008,.012,
.008695,.011939,
.009368,.011759,
.01,.011464,
.010571,.011064,
.011064,.010571,
.011464,.01,
.011759,.009368,
.011939,.008695,
.012,.008,
.012,-.008,
.011939,-.008695,
.011759,-.009368,
.011464,-.01,
.011064,-.010571,
.010571,-.011064,
.01,-.011464,
.009368,-.011759,
.008695,-.011939,
.008,-.012,
0.0*
%
%ADD19MACRO19*%
%ADD65C,.012*%
%ADD66C,.03*%
%ADD67C,.04*%
%ADD68C,.014*%
%ADD69C,.015*%
%ADD70C,.025*%
%ADD71C,.018*%
%ADD72C,.004*%
%ADD73C,.006*%
%ADD80C,.05204*%
%ADD77C,.07004*%
%ADD78C,.04604*%
%ADD79C,.07404*%
%ADD84C,.08504*%
%ADD83C,.07904*%
%ADD76C,.08606*%
%ADD75C,.10306*%
%ADD85R,.008X.008*%
%ADD81C,.18204*%
%ADD82C,.23704*%
%ADD74C,.18206*%
G75*
%LPD*%
G75*
G36*
G01X-139900Y215800D02*
X-140600Y216500D01*
Y338800D01*
X-140100Y339300D01*
X-61900D01*
X-59900Y340100D01*
X-57900Y341500D01*
X-56600Y343400D01*
X-56100Y345200D01*
X-56000Y346300D01*
Y504100D01*
X-55300Y504800D01*
X-3400D01*
X-1500Y505100D01*
X700Y506400D01*
X2300Y508400D01*
X3100Y510900D01*
Y551193D01*
G02X3819Y551434I400J0D01*
G03Y555654I2795J2110D01*
G02X3100Y555895I-319J241D01*
G01Y669303D01*
G02X3819Y669544I400J0D01*
G03Y673764I2795J2110D01*
G02X3100Y674005I-319J241D01*
G01Y783500D01*
X3900Y784300D01*
X77800D01*
X81800Y788300D01*
Y921300D01*
X82600Y922100D01*
X755700D01*
X756800Y921000D01*
Y818300D01*
X760700Y814400D01*
X764900D01*
X765400Y813900D01*
Y811100D01*
X764900Y810600D01*
X760600D01*
X747880Y823320D01*
Y851080D01*
X749400Y852600D01*
Y861300D01*
X744550Y866150D01*
X743150D01*
X743143Y866157D01*
X671428D01*
X657926Y852655D01*
Y839560D01*
X657450D01*
X646644Y828753D01*
X646551Y828762D01*
G03X648635Y826678I-209J-2293D01*
G01X648626Y826771D01*
X657243Y835388D01*
G02X657926Y835105I283J-283D01*
G01Y740131D01*
X661006Y737051D01*
X676404D01*
X683037Y743684D01*
X728716D01*
X737500Y734900D01*
X755000D01*
X756700Y733200D01*
Y660300D01*
X757600Y659400D01*
Y658300D01*
X756700Y657400D01*
X716300D01*
X715200Y656300D01*
Y639622D01*
X714600Y639022D01*
X266862D01*
X187130Y559290D01*
G02X186464Y559688I-283J282D01*
G03X183825Y557049I-3783J1144D01*
G02X184223Y556383I116J-383D01*
G01X168509Y540669D01*
X149556D01*
X144818Y545407D01*
Y728446D01*
X192895Y776523D01*
Y854321D01*
X178724Y868492D01*
X174293D01*
G02X174047Y869208I0J400D01*
G03X162883I-5582J7189D01*
G02X162637Y868492I-246J-316D01*
G01X138667D01*
X135044Y864869D01*
Y820761D01*
X123964Y809681D01*
Y713688D01*
X121833Y711557D01*
X111790D01*
X87425Y735922D01*
G03X84259Y737768I-5091J-5094D01*
G01X84209Y737782D01*
X77193Y744798D01*
X55033D01*
X46190Y735955D01*
Y679800D01*
X45600Y679210D01*
Y671023D01*
X49653Y666970D01*
X51100D01*
X51470Y666600D01*
X52187D01*
X52213Y666593D01*
G03X54503Y666288I2292J8460D01*
G01X57839D01*
G02X58898Y666029I-1J-2298D01*
G01X82109Y642819D01*
G02X82049Y642204I-283J-283D01*
G03X85660Y638593I1451J-2160D01*
G02X86275Y638653I332J-223D01*
G01X97564Y627364D01*
Y615000D01*
X96565Y614001D01*
X90608D01*
X87371Y617238D01*
G03X84940Y619115I-8503J-8500D01*
G01X84917Y619128D01*
X76229Y627816D01*
X53221D01*
X42461Y617056D01*
Y568600D01*
X39300Y565439D01*
Y558100D01*
X39392Y558008D01*
Y546708D01*
X38678Y545994D01*
X27758D01*
X22378Y540614D01*
Y513498D01*
X25653Y510223D01*
X32541D01*
X32578Y510207D01*
G03X34622I1022J2393D01*
G01X34659Y510223D01*
X37477D01*
X40400Y507300D01*
X49200D01*
X53600Y511700D01*
Y513417D01*
X53607Y513442D01*
G03X53661Y513705I-2224J594D01*
G01X53670Y513770D01*
X56400Y516500D01*
Y518539D01*
X56900Y519039D01*
X63261D01*
X65500Y516800D01*
X69151D01*
X70162Y515789D01*
Y511581D01*
X67711Y509130D01*
X60700D01*
X55675Y504105D01*
X48995D01*
X48895Y504005D01*
X47305D01*
X46700Y503400D01*
Y496500D01*
X47324Y495876D01*
X54113D01*
X56002Y497764D01*
X57307D01*
X57389Y497846D01*
X58677D01*
G03X59338Y497989I-1J1602D01*
G01X59377Y498007D01*
X60772D01*
X61192Y497587D01*
X61187Y497497D01*
G03X61184Y497398I1598J-98D01*
G01Y495798D01*
G03X61282Y495245I1601J-1D01*
G01X61326Y495125D01*
X60825Y494624D01*
X58934D01*
X53465Y489155D01*
X47494D01*
X42182Y494467D01*
X42191Y494560D01*
G03X39360Y497391I-2591J240D01*
G01X39267Y497382D01*
X38778Y497871D01*
X34851D01*
X32588Y495608D01*
Y495079D01*
X32582Y495054D01*
G03Y493746I2518J-654D01*
G01X32588Y493721D01*
Y483901D01*
X32476Y483846D01*
G03X31460Y479670I1239J-2513D01*
G02X31138Y479033I-322J-237D01*
G01X25096D01*
X21313Y475250D01*
Y471894D01*
X16146Y466727D01*
X13827D01*
X1100Y454000D01*
Y281573D01*
G02X337Y281404I-400J0D01*
G03Y273714I-8250J-3845D01*
G02X1100Y273545I363J-169D01*
G01Y217400D01*
X-500Y215800D01*
X-139900D01*
G37*
G36*
G01X4100Y3100D02*
X3100Y4100D01*
Y172600D01*
X4600Y174100D01*
X11200D01*
X14100Y171200D01*
Y171000D01*
X18600Y166500D01*
Y57100D01*
X21200Y54500D01*
X34400D01*
X36900Y52000D01*
Y39900D01*
X46000Y30800D01*
X70831D01*
G02X71025Y30050I0J-400D01*
G03X82519I5747J-10365D01*
G02X82713Y30800I194J350D01*
G01X94100D01*
X95400Y32100D01*
Y57394D01*
X96600Y58594D01*
X171824D01*
X176917Y53501D01*
Y46900D01*
X178717Y45100D01*
X212481D01*
X217681Y50300D01*
Y53196D01*
X220356Y55871D01*
X220424Y55880D01*
G03X221742Y59807I-293J2283D01*
G01X221682Y59866D01*
Y61576D01*
X218736Y64522D01*
Y89211D01*
X214702Y93244D01*
Y102182D01*
X217426Y104906D01*
X221809D01*
X234972Y91742D01*
Y75428D01*
X245410Y64990D01*
X259140D01*
X265450Y71300D01*
Y82650D01*
X263400Y84700D01*
X259300D01*
X258200Y85800D01*
Y88200D01*
X253900Y92500D01*
X239300D01*
X219600Y112200D01*
X209355D01*
X197300Y124255D01*
X182558D01*
X180312Y126502D01*
X166128D01*
X165100Y127529D01*
X131429D01*
X128400Y124500D01*
Y102200D01*
X126600Y100400D01*
X94600D01*
X92500Y102500D01*
Y145690D01*
X87744Y150446D01*
X87802Y150573D01*
G03X87532Y152951I-2089J967D01*
G01X87490Y153005D01*
Y154000D01*
X75000Y166490D01*
Y184684D01*
X75001Y184694D01*
G03X75008Y184841I-1595J150D01*
G01Y186241D01*
G03X75001Y186388I-1602J-3D01*
G01X75000Y186398D01*
Y189411D01*
X75160Y189444D01*
G03X74775Y194001I-459J2256D01*
G01X74696Y194004D01*
X72500Y196200D01*
Y199216D01*
Y199219D01*
G03Y199381I-2300J81D01*
G01Y199384D01*
Y199413D01*
X72495Y199473D01*
Y199474D01*
G03X68949Y201232I-2295J-174D01*
G01X68899Y201200D01*
X65300D01*
X64646Y201854D01*
X64654Y201947D01*
G03X64660Y202089I-1595J139D01*
G01Y203489D01*
G03X64607Y203904I-1602J6D01*
G01X64600Y203929D01*
Y205817D01*
X64605Y205840D01*
Y205841D01*
X64610Y205863D01*
G03X64648Y206209I-1563J347D01*
G01Y207609D01*
G03X64610Y207955I-1601J-1D01*
G01X64605Y207977D01*
Y207978D01*
X64600Y208001D01*
Y208300D01*
X65100Y208800D01*
X68200D01*
X72921Y213521D01*
X158900D01*
X176283Y230904D01*
X176302Y230916D01*
G03X177005Y231619I-1238J1941D01*
G01X177017Y231638D01*
X177386Y232007D01*
Y241114D01*
X177886Y241614D01*
X182386D01*
X182700Y241300D01*
Y235900D01*
X183600Y235000D01*
X186800D01*
X188300Y236500D01*
Y245158D01*
X194803Y251661D01*
X195631D01*
X199303Y255333D01*
Y264453D01*
X190066Y273690D01*
Y280160D01*
G02X190619Y280529I400J0D01*
G03X191157Y285494I996J2404D01*
G01X191054Y285476D01*
X190556Y285974D01*
X190546Y286038D01*
G03X190107Y287066I-2273J-363D01*
G01X190066Y287120D01*
Y288556D01*
X190077Y288588D01*
G03Y290278I-2462J845D01*
G01X190066Y290310D01*
Y308458D01*
X192493Y310885D01*
X750615D01*
X756600Y304900D01*
Y4500D01*
X755200Y3100D01*
X4100D01*
G37*
G36*
G01X53993Y33700D02*
X53946Y33746D01*
X49354D01*
X40400Y42700D01*
Y78000D01*
X42300Y79900D01*
X50400D01*
X51364Y80864D01*
X78865D01*
X82500Y84499D01*
X117905D01*
X143430Y110024D01*
X170876D01*
X171172Y109728D01*
Y61828D01*
X170484Y61141D01*
X169943Y60600D01*
X94400D01*
X93300Y59500D01*
Y35000D01*
X92000Y33700D01*
X53993D01*
G37*
G36*
G01X212100Y48000D02*
X180798D01*
X179298Y49500D01*
Y63200D01*
X174300Y68198D01*
Y108300D01*
X175200Y109200D01*
X191000D01*
X197000Y103200D01*
Y90200D01*
X200400Y86800D01*
X204165D01*
X208065Y82900D01*
Y82883D01*
X210015Y80933D01*
X212967D01*
X213950Y79950D01*
Y49850D01*
X212100Y48000D01*
G37*
G36*
G01X196900Y473500D02*
X185900Y484500D01*
Y516400D01*
X193194Y523694D01*
G02X193776Y523676I283J-283D01*
G03X197026Y526926I1723J1527D01*
G02X197008Y527508I265J299D01*
G01X257000Y587500D01*
X588500D01*
X589400Y586600D01*
Y579200D01*
X579000Y568800D01*
X458000D01*
X439000Y549800D01*
X286100D01*
X270300Y534000D01*
Y511700D01*
X259700Y501100D01*
X229178D01*
X229151Y501108D01*
G03X227849I-651J-2208D01*
G01X227822Y501100D01*
X225500D01*
X221300Y496900D01*
Y483900D01*
X210900Y473500D01*
X196900D01*
G37*
G36*
G01X288800Y387300D02*
X287400Y388700D01*
Y395200D01*
X309600Y417400D01*
Y429000D01*
X354050Y473450D01*
X356750D01*
X366700Y483400D01*
Y485185D01*
X367758Y486242D01*
X403458D01*
X405200Y484500D01*
Y457900D01*
X405900Y457200D01*
Y456700D01*
X406100Y456500D01*
X412800D01*
X412900Y456600D01*
Y459600D01*
X413000Y459700D01*
X425600D01*
Y456500D01*
X425700Y456400D01*
X432592D01*
X432625Y456240D01*
G03X434194Y454960I1569J322D01*
G01X435794D01*
G03X436132Y454996I0J1601D01*
G01X436153Y455000D01*
X442100D01*
X443700Y456600D01*
Y484100D01*
X446400Y486800D01*
X454783D01*
X454791Y486608D01*
G03X459391I2300J91D01*
G01X459399Y486800D01*
X484400D01*
X494500Y476700D01*
Y458100D01*
X423700Y387300D01*
X288800D01*
G37*
G36*
G01X250400Y488296D02*
X250415Y488333D01*
G03X250569Y488910I-2128J877D01*
G01X250577Y488977D01*
X251117Y489517D01*
X251225Y489491D01*
G03X253995Y492261I530J2240D01*
G01X253969Y492369D01*
X255900Y494300D01*
X261300D01*
X276100Y509100D01*
Y528400D01*
X277200Y529500D01*
X281800D01*
X282941Y530641D01*
X283053Y530611D01*
G03X285000Y530962I605J2221D01*
G01X285052Y531000D01*
X466800D01*
X496400Y501400D01*
Y494320D01*
X496385Y494284D01*
G03X496297Y494032I2409J-983D01*
G01X496283Y493983D01*
X494600Y492300D01*
X493700D01*
X491465Y494535D01*
X491450Y494578D01*
G03X489878Y496150I-2450J-878D01*
G01X489835Y496165D01*
X487100Y498900D01*
X485782D01*
X485631Y499052D01*
X485486D01*
G02X485119Y499611I0J400D01*
G03X480897I-2111J918D01*
G02X480530Y499052I-367J-159D01*
G01X464248D01*
X456200Y507100D01*
X305900D01*
X279600Y480800D01*
X252300D01*
X250400Y482700D01*
Y488296D01*
G37*
G36*
G01X431400Y474000D02*
X427798Y477602D01*
X424878D01*
Y485518D01*
X436982D01*
X439598Y482902D01*
Y480066D01*
X433532Y474000D01*
X431400D01*
G37*
G36*
G01X407311Y457784D02*
Y483966D01*
X409588Y486242D01*
X420524D01*
X421190Y485577D01*
Y479020D01*
X420523Y478353D01*
X418295D01*
X417719Y477777D01*
Y474299D01*
X417199Y473779D01*
X415026D01*
X414280Y473033D01*
Y466290D01*
X415094Y465476D01*
X419217D01*
X419269Y465441D01*
G03X419754Y465185I1309J1893D01*
G01X419882Y465136D01*
Y460932D01*
X419876Y460926D01*
X411624D01*
Y457784D01*
X407311D01*
G37*
G36*
G01X749400Y440800D02*
X672000Y363400D01*
X445600D01*
X444000Y365000D01*
Y370000D01*
X530000Y456000D01*
X660000D01*
X660396Y455604D01*
X660405Y455593D01*
G03X660845Y455153I1761J1321D01*
G01X660856Y455144D01*
X661300Y454700D01*
X665907D01*
X665967Y454627D01*
G03X667434Y453808I1778J1462D01*
G01X667501Y453799D01*
X670161Y451139D01*
X670175Y451113D01*
G03X670809Y450259I3206J1718D01*
G03X671574Y449711I2041J2041D01*
G01X671604Y449696D01*
X672900Y448400D01*
Y438201D01*
X672894Y438176D01*
G03Y436890I2521J-643D01*
G01X672900Y436865D01*
Y435200D01*
X673900Y434200D01*
X677900D01*
X679600Y435900D01*
X694500D01*
X695000Y435400D01*
Y430200D01*
X696100Y429100D01*
X707500D01*
X715600Y437200D01*
Y445800D01*
X715937Y446137D01*
X715970Y446152D01*
G03X716832Y446750I-1220J2679D01*
G03X717430Y447612I-2081J2082D01*
G01X717445Y447645D01*
X720400Y450600D01*
Y451600D01*
X723706Y454906D01*
X723730Y454919D01*
G03X724361Y455354I-2042J3637D01*
G01X724417Y455400D01*
X730400D01*
X735900Y449900D01*
X741600D01*
X744000Y452300D01*
X769800D01*
X770700Y451400D01*
Y443300D01*
X768449Y441048D01*
X755276D01*
G03X753609Y440808I-1J-5901D01*
G01X753581Y440800D01*
X749400D01*
G37*
G36*
G01X503600Y504100D02*
X470100Y537600D01*
X450900D01*
X448300Y540200D01*
Y548455D01*
X463344Y563498D01*
X578702D01*
X581200Y561000D01*
Y549300D01*
X536000Y504100D01*
X503600D01*
G37*
G36*
G01X768462Y657038D02*
X768700Y656800D01*
Y649262D01*
X768219Y648781D01*
X768200Y648800D01*
X761800Y642400D01*
X718100D01*
X717400Y643100D01*
Y654400D01*
X718700Y655700D01*
X756762D01*
X758100Y657038D01*
X768462D01*
G37*
%LPC*%
G75*
G36*
G01X348952Y794966D02*
G03X348323I-314J-247D01*
G02Y797804I-1813J1419D01*
G03X348952I314J247D01*
G02Y794966I1813J-1419D01*
G37*
G36*
G01X237445Y793165D02*
G03X237178Y792578I82J-392D01*
G02X234697Y793708I-2009J-1123D01*
G03X234964Y794295I-82J392D01*
G02X237445Y793165I2009J1123D01*
G37*
G36*
G01X221962Y739354D02*
G03X221358Y739342I-297J-268D01*
G02X221299Y742358I-1768J1474D01*
G03X221903Y742370I297J268D01*
G02X221962Y739354I1768J-1474D01*
G37*
G36*
G01X48206Y743981D02*
X48181Y743967D01*
X41554Y737341D01*
Y709921D01*
X41583Y709874D01*
G02X41441Y706980I-2230J-1341D01*
G01X41402Y706927D01*
Y670812D01*
X48902Y663312D01*
Y646599D01*
X48934Y646549D01*
G02X44981Y644194I-1934J-1249D01*
G01X44967Y644219D01*
X44741Y644445D01*
X44572Y644276D01*
X44557Y644240D01*
G02X43810Y648235I-3415J1429D01*
G03X44498Y648512I288J277D01*
G01Y652826D01*
G03X43810Y653103I-400J0D01*
G02Y658235I-2668J2566D01*
G03X44498Y658512I288J277D01*
G01Y661488D01*
X36998Y668988D01*
Y707425D01*
X36981Y707464D01*
G02X37123Y709874I2372J1069D01*
G01X37152Y709921D01*
Y739165D01*
X45067Y747081D01*
X45081Y747106D01*
G02X48206Y743981I2019J-1106D01*
G37*
G36*
G01X83277Y635302D02*
X83658Y634920D01*
X83751Y634929D01*
G02X81978Y631466I209J-2292D01*
G03X81442Y631614I-345J-204D01*
G02X82335Y635387I-1242J2286D01*
G01X82395Y635302D01*
X83277D01*
G37*
G36*
G01X300673Y44190D02*
G03Y43510I211J-340D01*
G02X297927I-1373J-2210D01*
G03Y44190I-211J340D01*
G02X300673I1373J2210D01*
G37*
G36*
G01X284916Y45542D02*
G03X284296I-310J-253D01*
G02Y48836I-2014J1647D01*
G03X284916I310J253D01*
G02X288775Y49024I2014J-1647D01*
G03X289367Y49051I284J282D01*
G02X289528Y45559I2006J-1657D01*
G03X288936Y45532I-284J-282D01*
G02X284916Y45542I-2006J1657D01*
G37*
G36*
G01X253951Y100297D02*
G02X249423Y95769I-2264J-2264D01*
G01X206714Y138478D01*
X160311D01*
G02Y144882I0J3202D01*
G01X167914D01*
G03X168232Y145524I0J400D01*
G02X172372I2070J1576D01*
G03X172690Y144882I318J-242D01*
G01X209366D01*
X253951Y100297D01*
G37*
G36*
G01X207061Y127739D02*
G03X206741Y127259I71J-394D01*
G02X201663Y127276I-2541J-560D01*
G03X201356Y127755I-390J88D01*
G02X203937Y131919I544J2545D01*
G03X204563I313J249D01*
G02X207061Y127739I2037J-1619D01*
G37*
G36*
G01X105638Y164898D02*
X95604Y154864D01*
X95598Y154791D01*
G02X93124Y157265I-2295J179D01*
G01X93197Y157271D01*
X104228Y168302D01*
X113144D01*
X113204Y168366D01*
G02X117026I1911J-1766D01*
G01X117086Y168302D01*
X136014D01*
X140548Y172836D01*
Y179163D01*
X145720Y184334D01*
X169821D01*
X172751Y181405D01*
X172824Y181399D01*
G02X174586Y180341I-179J-2295D01*
G03X175206Y180274I337J216D01*
G01X175284Y180352D01*
X175291Y180360D01*
G02X175647Y180716I1796J-1440D01*
G01X175655Y180723D01*
X176054Y181122D01*
X176414D01*
X176441Y181130D01*
G02X177978Y176797I646J-2210D01*
G01X177942Y176782D01*
X175069Y173910D01*
X170878D01*
X169235Y172267D01*
X144978D01*
X144051Y171340D01*
X143865D01*
X137424Y164898D01*
X117086D01*
X117026Y164834D01*
G02X113204I-1911J1766D01*
G01X113144Y164898D01*
X105638D01*
G37*
G36*
G01X187722Y164655D02*
G03X187816Y165245I-216J337D01*
G02X188002Y168357I1784J1455D01*
G03X188010Y168637I-139J144D01*
G02X188165Y171916I1690J1563D01*
G03X188190Y172186I-133J149D01*
G02X191553Y171870I1828J1400D01*
G03X191528Y171600I133J-149D01*
G02X191298Y168543I-1828J-1400D01*
G03X191290Y168263I139J-144D01*
G02X190839Y164760I-1690J-1563D01*
G03X190745Y164170I216J-337D01*
G02X187722Y164655I-1784J-1455D01*
G37*
G36*
G01X221530Y175821D02*
G03X222182Y175768I345J203D01*
G02X221966Y173122I1766J-1476D01*
G03X221314Y173175I-345J-203D01*
G02X221530Y175821I-1766J1476D01*
G37*
G36*
G01X108452Y201872D02*
X101565Y194984D01*
X101568Y194897D01*
G02X98865Y192194I-2600J-103D01*
G01X98778Y192197D01*
X97277Y190696D01*
X86402D01*
G03X86056Y190097I1J-400D01*
G02X81320Y189587I-2256J-1297D01*
G03X80901Y190106I-381J121D01*
G02X82181Y194147I-216J2292D01*
G01X82237Y194100D01*
X95867D01*
X96371Y194604D01*
X96368Y194691D01*
G02X99071Y197394I2600J103D01*
G01X99158Y197391D01*
X108309Y206542D01*
X108315Y206615D01*
G02X112643Y205356I2295J-179D01*
G03X112724Y205086I177J-94D01*
G02X109101Y201750I-1242J-2286D01*
G03X108452Y201872I-366J-161D01*
G37*
G36*
G01X221432Y212733D02*
G03X221705Y212710I149J134D01*
G02X221414Y209366I1424J-1809D01*
G03X221141Y209389I-149J-134D01*
G02X221432Y212733I-1424J1809D01*
G37*
G36*
G01X717305Y28346D02*
X716791Y28322D01*
X716279D01*
X715765Y28346D01*
X715259Y28393D01*
X714746Y28462D01*
X714232Y28558D01*
X713729Y28681D01*
X713244Y28820D01*
X712757Y28984D01*
X712278Y29171D01*
X711807Y29380D01*
X711350Y29608D01*
X710898Y29861D01*
X710457Y30137D01*
X710040Y30427D01*
X709626Y30740D01*
X709237Y31071D01*
X708859Y31414D01*
X708495Y31784D01*
X708148Y32166D01*
X707824Y32566D01*
X707517Y32979D01*
X707231Y33405D01*
X706964Y33841D01*
X706717Y34291D01*
X706486Y34761D01*
X706287Y35237D01*
X706111Y35702D01*
X705945Y36197D01*
X705809Y36702D01*
X705698Y37205D01*
X705612Y37698D01*
X705541Y38207D01*
X705500Y38730D01*
X705482Y39241D01*
X705488Y39754D01*
X705518Y40268D01*
X705571Y40784D01*
X705653Y41293D01*
X705750Y41786D01*
X705875Y42297D01*
X706028Y42792D01*
X706195Y43269D01*
X706386Y43743D01*
X706599Y44217D01*
X706843Y44680D01*
X707095Y45116D01*
X707369Y45547D01*
X707670Y45972D01*
X707983Y46373D01*
X708318Y46768D01*
X708677Y47145D01*
X709043Y47499D01*
X709431Y47839D01*
X709837Y48163D01*
X710247Y48457D01*
X710670Y48741D01*
X711123Y49009D01*
X711575Y49246D01*
X712040Y49471D01*
X712512Y49663D01*
X712992Y49842D01*
X713492Y49996D01*
X713989Y50125D01*
X714485Y50228D01*
X714992Y50316D01*
X715508Y50376D01*
X716023Y50411D01*
X716535Y50423D01*
X717047Y50411D01*
X717562Y50376D01*
X718078Y50316D01*
X718585Y50228D01*
X719081Y50125D01*
X719578Y49996D01*
X720078Y49842D01*
X720558Y49663D01*
X721030Y49471D01*
X721495Y49246D01*
X721947Y49009D01*
X722400Y48741D01*
X722823Y48457D01*
X723233Y48163D01*
X723639Y47839D01*
X724027Y47499D01*
X724393Y47145D01*
X724752Y46768D01*
X725087Y46373D01*
X725400Y45972D01*
X725701Y45547D01*
X725975Y45116D01*
X726227Y44680D01*
X726471Y44217D01*
X726684Y43743D01*
X726875Y43269D01*
X727042Y42792D01*
X727195Y42297D01*
X727320Y41786D01*
X727417Y41293D01*
X727499Y40784D01*
X727552Y40268D01*
X727582Y39754D01*
X727588Y39241D01*
X727570Y38730D01*
X727529Y38207D01*
X727458Y37698D01*
X727372Y37205D01*
X727261Y36702D01*
X727125Y36197D01*
X726959Y35702D01*
X726783Y35237D01*
X726584Y34761D01*
X726353Y34291D01*
X726106Y33841D01*
X725839Y33405D01*
X725553Y32979D01*
X725246Y32566D01*
X724922Y32166D01*
X724575Y31784D01*
X724211Y31414D01*
X723833Y31071D01*
X723444Y30740D01*
X723030Y30427D01*
X722613Y30137D01*
X722172Y29861D01*
X721720Y29608D01*
X721263Y29380D01*
X720792Y29171D01*
X720313Y28984D01*
X719826Y28820D01*
X719341Y28681D01*
X718838Y28558D01*
X718324Y28462D01*
X717811Y28393D01*
X717305Y28346D01*
G37*
G36*
G01X245885Y532200D02*
G03X245500Y531785I15J-400D01*
G02X240900I-2300J-85D01*
G03X240485Y532200I-400J15D01*
G02X240092Y532219I-86J2300D01*
G03X239638Y531823I-54J-396D01*
G02X235363Y533014I-2302J5D01*
G03X235210Y533573I-343J207D01*
G02X234811Y537356I1090J2028D01*
G03X234870Y537903I-259J305D01*
G02X238660Y540508I1830J1397D01*
G03X239340I340J210D01*
G02X241885Y537074I1960J-1208D01*
G03X241752Y536363I102J-387D01*
G02X242700Y534415I-1352J-1863D01*
G03X243115Y534000I400J-15D01*
G02X243307I96J-2300D01*
G03X243515Y534223I9J200D01*
G02X245885Y532200I2285J277D01*
G37*
G36*
G01X236584Y514402D02*
G03X237185Y514325I334J221D01*
G02X236756Y510951I1739J-1935D01*
G03X236155Y511028I-334J-221D01*
G02X232375Y511349I-1739J1935D01*
G03X231755Y511359I-314J-248D01*
G02X231805Y514648I-1991J1675D01*
G03X232425Y514638I314J248D01*
G02X236584Y514402I1991J-1675D01*
G37*
G36*
G01X231026Y508876D02*
G03X231298Y508884I132J150D01*
G02X231399Y505507I1614J-1642D01*
G03X231127Y505499I-132J-150D01*
G02X228014Y505394I-1614J1642D01*
G03X227743Y505383I-130J-152D01*
G02X227614Y508758I-1628J1628D01*
G03X227885Y508769I130J152D01*
G02X231026Y508876I1628J-1628D01*
G37*
G36*
G01X210754Y503717D02*
G03X211239Y504031I92J389D01*
G02X212969Y501360I2261J-431D01*
G03X212484Y501046I-92J-389D01*
G02X210754Y503717I-2261J431D01*
G37*
G36*
G01X253563Y511463D02*
G02X248757Y510369I-2588J266D01*
G03X248089Y510390I-341J-209D01*
G02X243669Y513117I-2126J1500D01*
G03X243287Y513705I-353J189D01*
G02X245394Y515073I-187J2595D01*
G03X245776Y514485I353J-189D01*
G02X248181Y513250I187J-2595D01*
G03X248849Y513229I341J209D01*
G02X252309Y513963I2126J-1500D01*
G03X252912Y514266I205J344D01*
G02X254166Y511766I2588J-266D01*
G03X253563Y511463I-205J-344D01*
G37*
G36*
G01X427500Y429700D02*
X426100Y428300D01*
X385000D01*
X379400Y433900D01*
Y446800D01*
X374200Y452000D01*
Y471200D01*
X377600Y474600D01*
X377783D01*
X378117Y474934D01*
X388413D01*
X388747Y474600D01*
X388800D01*
X392000Y471400D01*
Y471347D01*
X392016Y471331D01*
Y461617D01*
X392000Y461601D01*
Y461200D01*
X389800Y459000D01*
Y451000D01*
X390600Y450200D01*
X412800D01*
X413100Y449900D01*
Y447400D01*
X413300Y447200D01*
X420800D01*
X421117Y446883D01*
X421127D01*
Y446873D01*
X421200Y446800D01*
Y446205D01*
X421214Y446191D01*
Y441035D01*
X421200Y441021D01*
Y440300D01*
X420200Y439300D01*
Y438600D01*
X420500Y438300D01*
X421800D01*
X422400Y438900D01*
Y446900D01*
X422700Y447200D01*
X425600D01*
Y450100D01*
X425700Y450200D01*
X426800D01*
X426892Y450108D01*
X432270D01*
Y450100D01*
X432400D01*
X433000Y449500D01*
Y448800D01*
X433500Y448300D01*
X433840D01*
X433862Y448305D01*
G02X434216Y448344I351J-1562D01*
G01X435816D01*
G02X436170Y448305I3J-1601D01*
G01X436192Y448300D01*
X441000D01*
X444400Y444900D01*
Y438900D01*
X438000Y432500D01*
X432100D01*
X429900Y434700D01*
X427700D01*
X427500Y434500D01*
Y429700D01*
G37*
G36*
G01X322124Y430728D02*
G03X322129Y430195I301J-264D01*
G02X318249Y430156I-1923J-1753D01*
G03X318244Y430689I-301J264D01*
G02X322124Y430728I1923J1753D01*
G37*
G36*
G01X369449Y422715D02*
G03X368830Y422678I-294J-271D01*
G02X368637Y425958I-2111J1521D01*
G03X369256Y425995I294J271D01*
G02X373381Y426120I2111J-1522D01*
G03X374001I310J253D01*
G02X377860Y426308I2014J-1647D01*
G03X378452Y426335I284J282D01*
G02X378613Y422843I2006J-1657D01*
G03X378021Y422816I-284J-282D01*
G02X374001Y422826I-2006J1657D01*
G03X373381I-310J-253D01*
G02X369449Y422715I-2014J1647D01*
G37*
G36*
G01X369383Y414999D02*
G03X368764Y414962I-294J-271D01*
G02X368571Y418242I-2111J1521D01*
G03X369190Y418279I294J271D01*
G02X373315Y418404I2111J-1522D01*
G03X373935I310J253D01*
G02X377794Y418592I2014J-1647D01*
G03X378386Y418619I284J282D01*
G02X378547Y415127I2006J-1657D01*
G03X377955Y415100I-284J-282D01*
G02X373935Y415110I-2006J1657D01*
G03X373315I-310J-253D01*
G02X369383Y414999I-2014J1647D01*
G37*
G36*
G01X369947Y406327D02*
G03X369328Y406290I-294J-271D01*
G02X369135Y409570I-2111J1521D01*
G03X369754Y409607I294J271D01*
G02X373879Y409732I2111J-1522D01*
G03X374499I310J253D01*
G02X378358Y409920I2014J-1647D01*
G03X378950Y409947I284J282D01*
G02X379111Y406455I2006J-1657D01*
G03X378519Y406428I-284J-282D01*
G02X374499Y406438I-2006J1657D01*
G03X373879I-310J-253D01*
G02X369947Y406327I-2014J1647D01*
G37*
G36*
G01X273442Y495003D02*
G03X272907Y494746I-151J-370D01*
G02X271573Y497530I-2207J654D01*
G03X272108Y497787I151J370D01*
G02X273442Y495003I2207J-654D01*
G37*
G36*
G01X475645Y384249D02*
G03X475666Y383978I157J-124D01*
G02X472299Y383711I-1560J-1693D01*
G03X472278Y383982I-157J124D01*
G02X472046Y387120I1560J1693D01*
G03X472028Y387391I-155J126D01*
G02X475397Y387623I1577J1677D01*
G03X475415Y387352I155J-126D01*
G02X475645Y384249I-1577J-1677D01*
G37*
G54D80*
X84900Y747900D03*
X85300Y755100D03*
X85000Y775900D03*
X84100Y769000D03*
X321300Y43200D03*
X351800Y42200D03*
X360500Y42600D03*
X330000Y42800D03*
X329900Y37100D03*
X321300D03*
X360500Y36700D03*
X351800Y36300D03*
X167015Y167633D03*
X158100Y166800D03*
X113815Y194333D03*
X136100Y173800D03*
X136291Y179968D03*
X126700Y173500D03*
X126300Y180209D03*
X122400Y199000D03*
X197900Y82000D03*
X264000Y513400D03*
X503300Y539700D03*
G54D77*
X10551Y623622D03*
Y741732D03*
X18425Y553544D03*
X32204D03*
X18425Y623622D03*
X32204D03*
X18425Y671654D03*
X32204D03*
X18425Y741732D03*
X32204D03*
G54D78*
X63862Y512438D03*
X57500Y662600D03*
X59379Y644787D03*
X64000Y765600D03*
X60122Y747800D03*
X223129Y764830D03*
X223596Y782163D03*
X228021Y787335D03*
X282413Y798410D03*
X271970Y798668D03*
X240130Y789012D03*
X305437Y798205D03*
X294148Y798547D03*
X315696Y798445D03*
X361814Y796557D03*
X668987Y731465D03*
X727300Y273200D03*
X722687Y120650D03*
X365131Y135484D03*
X373496Y140021D03*
X381025Y120650D03*
Y73748D03*
X362793Y126096D03*
Y77815D03*
X224664Y293860D03*
X231350Y222067D03*
X251700Y135484D03*
X152350Y131084D03*
X84641Y204036D03*
X106300Y105900D03*
X117500Y106200D03*
X111700Y106100D03*
X217899Y525103D03*
X206699Y525203D03*
X224515Y532633D03*
X324400Y570500D03*
X268215Y490733D03*
X288586Y493703D03*
X447307Y511890D03*
X469932Y518034D03*
X501800Y387600D03*
X500295Y401715D03*
X499764Y411324D03*
X497279Y382551D03*
X506100Y380000D03*
X523200Y399400D03*
X517041Y388700D03*
X536928Y411324D03*
X508306Y428179D03*
X637200Y393900D03*
X662100Y394600D03*
X482183Y535169D03*
X487073Y554094D03*
X483530Y541762D03*
X514073Y552477D03*
G54D79*
X41142Y635669D03*
Y763780D03*
Y753780D03*
Y773780D03*
G54D84*
X286982Y828335D03*
X276982D03*
X286982Y818335D03*
X276982D03*
X356982Y828335D03*
X346982D03*
X336982D03*
X326982D03*
X316982D03*
X306982D03*
X296982D03*
X356982Y818335D03*
X346982D03*
X336982D03*
X326982D03*
X316982D03*
X306982D03*
X296982D03*
X366982Y828335D03*
Y818335D03*
G54D83*
X182681Y580832D03*
G54D76*
X144843Y874449D03*
G54D75*
X-33503Y269685D03*
G54D85*
X68165Y514637D03*
X66847Y205809D03*
X66859Y203889D03*
X77206Y186641D03*
Y184441D03*
X415532Y476570D03*
G54D81*
X109410Y796831D03*
Y876397D03*
G54D82*
X108268Y905512D03*
X155512D03*
X29528Y19685D03*
G54D74*
X-59094Y277559D03*
%LPD*%
G75*
G36*
G01X377915Y452133D02*
X376315Y453733D01*
Y471433D01*
X378615Y473733D01*
X387915D01*
X390815Y470833D01*
Y462115D01*
X388300Y459600D01*
Y452600D01*
X387833Y452133D01*
X377915D01*
G37*
G36*
G01X386396Y429551D02*
X380879Y435068D01*
Y436857D01*
X380889Y436887D01*
G03Y438313I-2189J713D01*
G01X380879Y438343D01*
Y446004D01*
X382910Y448036D01*
X389060D01*
Y448933D01*
X406180D01*
Y448864D01*
X411624D01*
Y445722D01*
X419882D01*
Y441402D01*
X418847Y440367D01*
Y438078D01*
X422105Y434820D01*
X423476D01*
X423482D01*
G03X423582Y434816I114J1597D01*
G01X424982D01*
G03X425082Y434820I-14J1601D01*
G01X425088D01*
X426030D01*
X426285Y434564D01*
Y431630D01*
X424206Y429551D01*
X386396D01*
G37*
%LPC*%
G75*
G54D85*
X423182Y432618D03*
X425382D03*
%LPD*%
G75*
G54D10*
G01X80685Y192398D02*
X96572D01*
X98968Y194794D01*
G01D02*
X110610Y206436D01*
G01X172645Y179104D02*
X169116Y182633D01*
X146425D01*
X142250Y178458D01*
Y172131D01*
X136719Y166600D01*
X115115D01*
G01X93303Y154970D02*
X104933Y166600D01*
X115115D01*
G01X212028Y93512D02*
X217034Y88506D01*
Y61260D01*
X220131Y58163D01*
G01X210680Y84396D02*
X208115Y86961D01*
Y95933D01*
G01X210356Y99104D02*
Y98556D01*
X208115Y96315D01*
Y95933D01*
G01X428968Y448206D02*
X430594D01*
X432807Y445993D01*
X435016D01*
G01X434515Y436133D02*
X431015D01*
X430069Y437079D01*
X428616D01*
G01X424282Y437168D02*
X424343Y437229D01*
Y443581D01*
G01X428616Y437079D02*
X428527Y437168D01*
X424282D01*
G01X435016Y445993D02*
X438855D01*
X440715Y444133D01*
G01X707980Y464221D02*
X706681Y466020D01*
X701858D01*
G01X707980Y464221D02*
X707110Y464051D01*
X701858D01*
X-1011811Y-15748D03*
Y940945D03*
X-59094Y277559D03*
X-7913D03*
X-33503Y269685D03*
X54724Y557087D03*
Y620079D03*
Y675197D03*
Y738189D03*
X144843Y798779D03*
Y812994D03*
Y874449D03*
Y860234D03*
X716535Y39370D03*
X775591Y-15748D03*
Y940944D03*
G54D20*
X55700Y91200D03*
X59274Y91203D03*
X35230Y310338D03*
X134663Y460183D03*
X681300Y514000D03*
X648500Y540400D03*
X677800Y514000D03*
X725784Y558187D03*
G54D11*
X-944882Y-17185D03*
Y942382D03*
X57900Y226200D03*
X182900Y308800D03*
X708683Y-17218D03*
G54D21*
X74800Y87800D03*
X43851Y178828D03*
X43794Y193758D03*
X22900Y310200D03*
X39236Y280487D03*
X27000Y310100D03*
X31100D03*
X63942Y534279D03*
X67065Y515737D03*
X98138Y402278D03*
X89163Y386883D03*
X94076Y411254D03*
X118163Y470983D03*
X149799Y448926D03*
X428616Y433629D03*
X684869Y434811D03*
X680738Y434833D03*
X693509Y434901D03*
X689111Y434812D03*
X705600Y551200D03*
X663300Y526200D03*
X648200Y552100D03*
X705927Y528727D03*
X668699Y552630D03*
X726040Y547196D03*
G54D12*
X-138100Y222300D03*
Y241300D03*
Y260300D03*
Y279300D03*
Y298300D03*
Y317300D03*
Y336300D03*
X-70100Y222300D03*
X-87100D03*
X-104100D03*
X-121100D03*
X-70100Y241300D03*
X-87100D03*
X-104100D03*
X-121100D03*
X-70100Y260300D03*
X-87100D03*
X-104100D03*
X-121100D03*
X-70100Y279300D03*
X-87100D03*
X-104100D03*
X-121100D03*
X-70100Y298300D03*
X-87100D03*
X-104100D03*
X-121100D03*
X-70100Y317300D03*
X-87100D03*
X-104100D03*
X-121100D03*
X-70100Y336300D03*
X-87100D03*
X-104100D03*
X-121100D03*
X-2100Y222300D03*
X-19100D03*
X-36100D03*
X-53100D03*
X-2100Y241300D03*
X-19100D03*
X-36100D03*
X-53100D03*
X-2100Y260300D03*
X-19100D03*
X-36300Y260000D03*
X-53100Y260300D03*
X9243Y334400D03*
X-1900Y288300D03*
X-49400Y284500D03*
X-19600Y279500D03*
X-36100Y279300D03*
X-2100Y298300D03*
X-19100D03*
X-36100D03*
X-53100D03*
X-2100Y317300D03*
X-19100D03*
X-36100D03*
X-53100D03*
X-2100Y336300D03*
X-19100D03*
X-36100D03*
X-53100D03*
X-1600Y413600D03*
Y394600D03*
Y375600D03*
Y356600D03*
X-52600Y413600D03*
X-35600D03*
X-18600D03*
X-52600Y394600D03*
X-35600D03*
X-18600D03*
X-52600Y375600D03*
X-35600D03*
X-18600D03*
X-52600Y356600D03*
X-35600D03*
X-18600D03*
X-19400Y483400D03*
X-2400D03*
X-36400D03*
X-53400D03*
X-1500Y470300D03*
Y451300D03*
Y432300D03*
X-52500Y470300D03*
X-35500D03*
X-18500D03*
X-52500Y451300D03*
X-35500D03*
X-18500D03*
X-52500Y432300D03*
X-35500D03*
X-18500D03*
X8788Y453864D03*
X-19400Y502400D03*
X-2400D03*
X-36400D03*
X-53400D03*
X63400Y89300D03*
X51900Y83600D03*
X43980Y86200D03*
X68000Y87750D03*
X42700Y110500D03*
X67300Y107200D03*
X63100Y107300D03*
X48100Y133900D03*
X59200Y95573D03*
X51800Y93500D03*
X79600Y91500D03*
X51900Y89900D03*
X79500Y85700D03*
X77200Y95500D03*
X69800Y176800D03*
X31500Y185700D03*
X76250Y148850D03*
X70200Y199300D03*
X47900Y145500D03*
X48100Y153800D03*
X43800Y204800D03*
X38800Y194300D03*
X38700Y199700D03*
X73700D03*
X49500Y169300D03*
X61751Y181464D03*
X44100Y200600D03*
X49286Y203671D03*
X69000Y202700D03*
X77200Y189000D03*
X60200Y193550D03*
X29600Y200100D03*
X26100Y187300D03*
X39800Y172900D03*
X27800Y191100D03*
X74700Y191700D03*
X70675Y145000D03*
X60009Y255077D03*
X55624Y255132D03*
X59523Y271123D03*
X60102Y263180D03*
X55883Y263570D03*
X33400Y266400D03*
X59258Y246890D03*
X60069Y237965D03*
X64700Y215100D03*
X51600Y217000D03*
X50500Y243100D03*
X70636Y272953D03*
X79189Y235119D03*
X43900Y209000D03*
X72001Y265901D03*
X69400Y207400D03*
X76019Y222534D03*
X42507Y296616D03*
X59316Y300366D03*
X59096Y289139D03*
X59523Y281330D03*
X52257Y276649D03*
X55420Y288656D03*
X17100Y311700D03*
X43181Y278603D03*
X39563Y307968D03*
X21876Y282289D03*
X41418Y287473D03*
X61776Y367194D03*
X43345Y386857D03*
X43639Y374043D03*
X29700Y355000D03*
X27284Y358500D03*
X67527Y381818D03*
X43569Y379314D03*
X65605Y367307D03*
X51422Y473540D03*
X24315Y472668D03*
X47307Y465104D03*
X29064Y471345D03*
X55295Y479672D03*
X20715Y485712D03*
X20276Y477090D03*
X20928Y453864D03*
X21300Y468000D03*
X38800Y535700D03*
X38200Y528900D03*
X51383Y514037D03*
X63862Y512438D03*
X73542Y514340D03*
X37200Y513500D03*
X32026Y516764D03*
X60800Y505200D03*
X56121Y494271D03*
X21090Y497108D03*
X54659Y513125D03*
X67140Y511501D03*
X50893Y534434D03*
X66300Y548000D03*
X67244Y535455D03*
X72677Y528615D03*
X69220Y614992D03*
X59379Y644787D03*
X57500Y662600D03*
X47000Y645300D03*
X69911Y676938D03*
X73900Y664900D03*
X77000Y646200D03*
X72930Y645818D03*
X67257Y643668D03*
X60122Y747800D03*
X64000Y765600D03*
X47100Y746000D03*
X69217Y732676D03*
X73325Y760926D03*
X67809Y758190D03*
X65447Y711413D03*
X62066Y711051D03*
X65356Y707010D03*
X61193Y706973D03*
X73282Y778907D03*
X106300Y105900D03*
X81150Y120850D03*
X89400Y120800D03*
X85250Y120850D03*
X117500Y106200D03*
X85000Y107800D03*
X111700Y106100D03*
X89000Y107700D03*
X82400Y89500D03*
X132500Y124600D03*
X80685Y192398D03*
X84641Y204036D03*
X79900Y148700D03*
X103300Y160900D03*
X112000Y160700D03*
X119900Y162200D03*
X125300Y162300D03*
X122100Y203300D03*
X96900Y189286D03*
X107771Y182699D03*
X145400Y161955D03*
X114700Y157000D03*
X107672Y156597D03*
X98700Y156200D03*
X122200Y156700D03*
X80207Y139965D03*
X81200Y176000D03*
X93303Y154970D03*
X144950Y177338D03*
X85713Y151540D03*
X84900Y145300D03*
X125700Y225200D03*
X121000Y225300D03*
X109400Y225400D03*
X90813D03*
X79800Y225900D03*
X87227Y242891D03*
X87263Y264658D03*
X90652Y265960D03*
X87698Y246708D03*
X94051Y265872D03*
X91230Y247047D03*
X91819Y250396D03*
X94793Y252595D03*
X98211Y252758D03*
X142933Y251431D03*
X132651Y255357D03*
X138228Y260175D03*
X124933Y270414D03*
X136427Y251413D03*
X124874Y273953D03*
X137809Y247647D03*
X135592Y257933D03*
X116566Y254205D03*
X114229Y270684D03*
X119242Y252107D03*
X112042Y275903D03*
X121685Y249741D03*
X121741Y246341D03*
X118219Y274497D03*
X122572Y258147D03*
X121599Y274869D03*
X130567Y258051D03*
X113558Y261260D03*
X111008Y242830D03*
X106381Y259865D03*
X106504Y243329D03*
X103610Y268626D03*
X102713Y242975D03*
X103003Y260260D03*
X108652Y247260D03*
X107887Y266647D03*
X101242Y265901D03*
X100415Y246679D03*
X126611Y258265D03*
X84863Y229783D03*
X134529Y264470D03*
X137190Y266587D03*
X131901Y267444D03*
X132163Y271041D03*
X137690Y273752D03*
X110610Y206436D03*
X125600Y221200D03*
X113863Y228669D03*
X102559Y228575D03*
X97885Y228339D03*
X147013Y225483D03*
X122000Y207300D03*
X94600Y206900D03*
X94548Y211258D03*
X109534Y314564D03*
X92682Y331571D03*
X140103Y328216D03*
X117460Y335158D03*
X128964Y339470D03*
X148102Y338366D03*
X119603Y285731D03*
X124478Y280855D03*
X95202Y290958D03*
X98565Y290455D03*
X102107Y290439D03*
X105603Y291092D03*
X95146Y279609D03*
X110808Y291075D03*
X98546Y279609D03*
X114915Y290203D03*
X104413Y278608D03*
X117027Y278475D03*
X148834Y284832D03*
X107750Y277953D03*
X128918Y307533D03*
X135308Y276806D03*
X139784Y276432D03*
X142241Y278783D03*
X121477Y314973D03*
X135613Y308903D03*
X95400Y383083D03*
X84200Y380000D03*
X118744Y525279D03*
X140399Y525238D03*
X129199Y525271D03*
X107103Y525057D03*
X95599Y525026D03*
X84799Y524898D03*
X90878Y585185D03*
X85654Y659044D03*
X83960Y632636D03*
X90681Y690157D03*
X90174Y678675D03*
X85600Y647837D03*
X93840Y699686D03*
X90814Y734451D03*
X91027Y724985D03*
X91094Y715818D03*
X84703Y758885D03*
X84182Y764879D03*
X90746Y712435D03*
X90947Y709040D03*
X91003Y705214D03*
X91130Y701741D03*
X220131Y58163D03*
X201237Y106350D03*
X210356Y99104D03*
X210680Y84396D03*
X212028Y93512D03*
X212800Y125800D03*
X182400Y128300D03*
X175598Y128436D03*
X220100Y123600D03*
X166700Y128800D03*
X172200Y128300D03*
X179000D03*
X205628Y89404D03*
X152350Y131084D03*
X204849Y106438D03*
X200100Y101200D03*
X160311Y141680D03*
X219548Y174651D03*
X189600Y166700D03*
X189700Y170200D03*
X190018Y173586D03*
X188961Y162715D03*
X211700Y181600D03*
X208200Y153500D03*
X203900D03*
X200100Y146500D03*
Y150400D03*
X199100Y153800D03*
X194800D03*
X174339Y151172D03*
X178400Y152300D03*
X172645Y179104D03*
X177087Y178920D03*
X183120Y266103D03*
X183082Y271969D03*
X182853Y256107D03*
X183956Y261452D03*
X168010Y267909D03*
X219717Y211198D03*
X182177Y251208D03*
X154300Y227900D03*
X171200Y233000D03*
X185563Y245456D03*
X175064Y232857D03*
X185740Y240983D03*
X185502Y237383D03*
X152663Y272053D03*
X192284Y258847D03*
X150666Y243134D03*
X195698Y259749D03*
X196365Y256414D03*
X168324Y246397D03*
X171762Y258345D03*
X167894Y243024D03*
X167760Y239626D03*
X156800Y230500D03*
X152663Y267791D03*
X216335Y218212D03*
X196344Y237383D03*
X196078Y248183D03*
X196021Y244556D03*
X196151Y240983D03*
X151519Y250193D03*
X180641Y231683D03*
X186319Y268076D03*
X183043Y276658D03*
X183707Y289861D03*
X183653Y283162D03*
X184188Y340638D03*
X162135Y332650D03*
X185042Y286734D03*
X167051Y293752D03*
X188273Y285674D03*
X187118Y281963D03*
X163142Y294193D03*
X183466Y294017D03*
X152580Y285530D03*
X172818Y288683D03*
X216178Y411331D03*
X219144Y414536D03*
X195307Y355649D03*
X206775Y348954D03*
X173508Y348462D03*
X177715Y397471D03*
X212500Y395500D03*
X217800Y395900D03*
X200161Y416474D03*
X206142Y413945D03*
X206871Y397177D03*
X210042Y412265D03*
X175767Y380311D03*
X189073Y380379D03*
X185276Y380362D03*
X181242Y380481D03*
X197565Y380257D03*
X203379Y380312D03*
X169600Y380500D03*
X173864Y397677D03*
X213400Y434601D03*
X181980Y458681D03*
X210772Y431456D03*
X200453Y439066D03*
X203186Y451492D03*
X180445Y422567D03*
X176991Y463723D03*
X184750Y427953D03*
X208947Y443700D03*
X196803Y444462D03*
X201400Y434400D03*
X202764Y444274D03*
X190887Y424438D03*
X174500Y424100D03*
X182060Y443776D03*
X211243Y462005D03*
X203406Y454885D03*
X195038Y477148D03*
X180313Y446694D03*
X176915Y446556D03*
X195400Y452051D03*
X208632Y457048D03*
X181034Y427967D03*
X177700Y427300D03*
X184399Y525203D03*
X195499D03*
X206699D03*
X217899Y525103D03*
X162615Y525220D03*
X173537D03*
X151684Y525258D03*
X210223Y501477D03*
X213500Y503600D03*
X216300Y499600D03*
X193016Y496643D03*
X219492Y517832D03*
X219590Y740816D03*
X181642Y837321D03*
Y827853D03*
X181772Y818429D03*
X159926Y813000D03*
X201663Y827680D03*
X201142Y837191D03*
X181081Y856307D03*
X181124Y847013D03*
X200798Y846849D03*
X266700Y46900D03*
X263000Y47000D03*
X257500Y46900D03*
X253800Y47000D03*
X244900Y47300D03*
X248600Y47200D03*
X235000Y47500D03*
X238700Y47400D03*
X225231Y58420D03*
X254498Y88487D03*
X251687Y98033D03*
X261830Y81230D03*
X241101D03*
X256928Y69301D03*
X241132Y85023D03*
X259815Y94233D03*
X248000Y114500D03*
X223948Y174292D03*
X246100Y151300D03*
Y155800D03*
Y160400D03*
X231049Y188760D03*
X251700Y135484D03*
X231350Y222067D03*
X238614Y217763D03*
X222496Y222320D03*
X223129Y210901D03*
X224664Y293860D03*
X257400Y403206D03*
X239600Y405600D03*
X237800Y411200D03*
X226576Y401835D03*
X228243Y380358D03*
X231915Y380533D03*
X244928Y367685D03*
X238151Y356092D03*
X228510Y367624D03*
X240715Y380333D03*
X222269Y402278D03*
X228949Y410741D03*
X225421Y410908D03*
X269840Y386256D03*
X239693Y396029D03*
X257500Y399300D03*
X264600Y380500D03*
X270800Y408500D03*
X261300Y402355D03*
X275500Y415400D03*
X264124Y408219D03*
X258267Y408800D03*
X233400Y409700D03*
X255010Y367624D03*
X273554Y386722D03*
X223600Y456200D03*
X246502Y472752D03*
X255622Y461532D03*
X263000Y438800D03*
X260600Y435900D03*
X258299Y432800D03*
X250400Y440000D03*
X249600Y428100D03*
X237700Y458000D03*
X269300Y486200D03*
X249600Y432500D03*
X239000Y440300D03*
X244800Y454500D03*
X229600Y460700D03*
X289200Y445100D03*
X252200Y486700D03*
X290300Y462400D03*
X290011Y456234D03*
X289000Y449200D03*
X221035Y453935D03*
X279120Y440440D03*
X276761Y443421D03*
X277575Y449398D03*
X270714Y458323D03*
X263719Y455536D03*
X259779Y456823D03*
X220768Y418393D03*
X260322Y462288D03*
X256852Y465331D03*
X258221Y469246D03*
X235069Y464940D03*
X257184Y421241D03*
X271342Y440630D03*
X235600Y433300D03*
X264775Y459236D03*
X279789Y432846D03*
X285565Y438912D03*
X250400Y473300D03*
X260481Y473769D03*
X253214Y469048D03*
X228400Y486400D03*
X228001Y474064D03*
X226000Y458700D03*
X249845Y469508D03*
X229300Y442500D03*
X225700Y496800D03*
X226115Y507011D03*
X229513Y507141D03*
X232912Y507242D03*
X224515Y532633D03*
X237336Y531828D03*
X236700Y539300D03*
X240400Y534500D03*
X245800D03*
X241300Y539300D03*
X236300Y535600D03*
X243200Y531700D03*
X288586Y493703D03*
X268215Y490733D03*
X251755Y491731D03*
X270700Y495400D03*
X274315Y497133D03*
X283657Y532832D03*
X280259Y532714D03*
X232200Y492100D03*
X231739Y495469D03*
X248286Y489208D03*
X242100Y489000D03*
X268600Y529800D03*
X256300Y531400D03*
X289400Y511700D03*
X243300Y527900D03*
X247256Y529218D03*
X251700Y531500D03*
X268500Y525800D03*
X238118Y492166D03*
X246132Y492160D03*
X289405Y515437D03*
X228500Y498900D03*
X281183Y592936D03*
X223671Y740896D03*
X228249Y761450D03*
X223129Y764830D03*
X271970Y798668D03*
X282413Y798410D03*
X228021Y787335D03*
X223596Y782163D03*
X236973Y795418D03*
X237950Y774979D03*
X237815Y779065D03*
X226949Y782735D03*
X235169Y791455D03*
X240130Y789012D03*
X277254Y852624D03*
X314000Y405200D03*
X316800Y415900D03*
X299800Y398500D03*
X332600Y400100D03*
X305456Y481787D03*
X335532Y485626D03*
X323215Y485633D03*
X304783Y467192D03*
X295115Y476433D03*
Y473033D03*
X297715Y479588D03*
X306603Y459523D03*
X301437Y426833D03*
X304200Y432600D03*
X300603Y432406D03*
X309200Y444700D03*
X331800Y440400D03*
X331900Y444600D03*
X356700Y437500D03*
X348800D03*
X341500Y437400D03*
X291300Y468600D03*
X308900Y449100D03*
X327900Y438100D03*
X341430Y459351D03*
X345735Y460843D03*
X349800Y460000D03*
X353698Y460323D03*
X357812Y460406D03*
X297238Y429641D03*
X304550Y424222D03*
X300059Y422844D03*
X318015Y493833D03*
X334315Y496733D03*
X330815Y493433D03*
X327115Y489533D03*
X344815Y494933D03*
X321415Y497133D03*
X304000Y538500D03*
X308800Y540925D03*
X350400Y512000D03*
X335600Y511400D03*
X304700Y509500D03*
X317900Y520100D03*
X314628Y517729D03*
X343905Y519116D03*
X324400Y570500D03*
X346510Y796385D03*
X350765D03*
X315696Y798445D03*
X294148Y798547D03*
X305437Y798205D03*
X362793Y77815D03*
Y126096D03*
X381025Y73748D03*
Y120650D03*
X373496Y140021D03*
X365131Y135484D03*
X413900Y396400D03*
X428343Y463067D03*
X420575Y467336D03*
X382695Y467033D03*
Y471133D03*
X388884Y468631D03*
X387143Y462647D03*
X378700Y437600D03*
X371200Y437800D03*
X363800Y437700D03*
X428616Y429466D03*
X391500Y459000D03*
X399900Y458600D03*
X421273Y439381D03*
X361533Y460222D03*
X365241Y460010D03*
X416588Y467839D03*
X361814Y796557D03*
X500295Y401715D03*
X501800Y387600D03*
X473838Y385675D03*
X474106Y382285D03*
X500526Y394177D03*
X473605Y389068D03*
X499764Y411324D03*
X497279Y382551D03*
X435138Y460661D03*
X457091Y486699D03*
X475600Y462100D03*
X452300Y420900D03*
X458900Y446600D03*
X483100Y449900D03*
X488500Y474200D03*
X450300Y459900D03*
X471300Y482200D03*
X449000Y480000D03*
X438316Y449493D03*
X438294Y453811D03*
X501700Y477200D03*
X483530Y541762D03*
X487073Y554094D03*
X482183Y535169D03*
X483008Y500529D03*
X469932Y518034D03*
X447307Y511890D03*
X447090Y497242D03*
X471410Y490049D03*
X498994Y488322D03*
X501802Y490240D03*
X494400Y493600D03*
Y497500D03*
X471650Y493916D03*
X494410Y501344D03*
X458713Y518034D03*
X482200Y529100D03*
X484200Y538000D03*
X483800Y545700D03*
X452652Y495705D03*
X465900Y501200D03*
X523200Y399400D03*
X506100Y380000D03*
X517041Y388700D03*
X513500Y399060D03*
X520900Y388100D03*
X536928Y411324D03*
X514000Y486293D03*
X508306Y428179D03*
X523462Y423957D03*
X503923Y423910D03*
X536736Y418540D03*
X504500Y479500D03*
X514073Y552477D03*
X529000Y550500D03*
X502318Y535328D03*
X521002Y555911D03*
X525300Y552800D03*
X516900Y561200D03*
X528000Y562900D03*
X512700Y560000D03*
X637200Y393900D03*
X629100Y536000D03*
X632600Y555200D03*
X636200Y555100D03*
X640100Y550600D03*
X638300Y511800D03*
X641800Y519000D03*
X639500Y521900D03*
X641700Y510300D03*
X662100Y394600D03*
X667979Y486293D03*
X702400Y431500D03*
X698300Y431600D03*
X702000Y485700D03*
X688615Y485133D03*
X693509Y431701D03*
X689111Y431612D03*
X684869Y431611D03*
X680738Y431633D03*
X711409Y467621D03*
X707700Y476500D03*
X707890Y467821D03*
X684259Y476130D03*
X682774Y449737D03*
X667745Y456089D03*
X662604Y463284D03*
X671915Y543133D03*
X694700Y547700D03*
X688800Y540450D03*
X702400Y554800D03*
X705927Y538650D03*
X663600Y535395D03*
X644600Y556700D03*
X652400Y545200D03*
X674375Y509826D03*
X700512Y510204D03*
X643833Y549325D03*
X702000Y546581D03*
X702400Y550600D03*
X684600Y542100D03*
X682015Y493633D03*
X665499Y556600D03*
X651800Y540295D03*
X711400Y515400D03*
X711900Y521500D03*
X675400Y538100D03*
X662200Y547300D03*
X709600Y524100D03*
X658314Y526697D03*
X672168Y538889D03*
X676115Y542633D03*
X712102Y542133D03*
X707589Y515400D03*
X700900Y539500D03*
X669200Y559600D03*
X656817Y567131D03*
X697600Y560000D03*
X701400Y560200D03*
X707391Y564566D03*
X643100Y589900D03*
X689945Y758289D03*
X700989Y759255D03*
X667982Y739870D03*
X681402Y757754D03*
X663575Y742289D03*
X668987Y731465D03*
X691075Y820814D03*
X711116Y796516D03*
X702290Y820921D03*
X680480Y773302D03*
X678755Y784815D03*
X676727Y790555D03*
X679630Y795856D03*
X680239Y802378D03*
X682693Y806283D03*
X684732Y810518D03*
X669886Y786112D03*
X666516Y784722D03*
X686308Y834802D03*
X646342Y826469D03*
X685799Y770894D03*
X690211Y827401D03*
X683715Y852233D03*
X710727Y862002D03*
X678351Y854383D03*
X679332Y841866D03*
X681156Y844982D03*
X681542Y848361D03*
X722687Y120650D03*
X727300Y273200D03*
X758200Y338900D03*
X756700Y370600D03*
X762900Y387400D03*
X768000Y457700D03*
X767700Y473300D03*
X729700Y551500D03*
X729600Y540400D03*
X724000Y532600D03*
X722682Y538700D03*
X716300Y517125D03*
X719800Y525000D03*
X719866Y528656D03*
X751965Y522097D03*
X747886D03*
X757848Y513543D03*
X752874Y534854D03*
X737297Y517903D03*
X756523Y520272D03*
X749493Y535216D03*
X725100Y519600D03*
X746000Y549700D03*
X726800Y527400D03*
X723538Y526440D03*
X742607Y549481D03*
X752100Y506500D03*
X749500Y508800D03*
X742000Y505000D03*
X762275Y512870D03*
X744073Y522097D03*
X755862Y516303D03*
X756400Y508100D03*
X756272Y534995D03*
X763000Y490800D03*
X717879Y564572D03*
X725900Y561800D03*
X737400Y576200D03*
X766358Y564600D03*
X727700Y584400D03*
X758400Y568500D03*
X742600Y577100D03*
X756100Y658700D03*
X757600Y639700D03*
X746669Y740179D03*
X743653Y744114D03*
X741453Y748054D03*
X738850Y751989D03*
X734450Y755929D03*
X730967Y759864D03*
X724305Y770450D03*
X723678Y774016D03*
X727477Y775212D03*
X724733Y779559D03*
X730028Y782297D03*
X724859Y784497D03*
X742663Y788885D03*
X729988Y787114D03*
X739510Y795264D03*
X725239Y788970D03*
X745230Y793211D03*
X729486Y791416D03*
X742370Y799077D03*
X725407Y794540D03*
X747659Y796960D03*
X744790Y802781D03*
X749593Y803991D03*
X747556Y808994D03*
X749629Y812608D03*
X722443Y826463D03*
X721704Y829981D03*
X724858Y831254D03*
X723801Y834857D03*
X726332Y837128D03*
X733066Y836450D03*
X729250Y850000D03*
X721243Y850725D03*
X718263Y863827D03*
X745100Y859405D03*
X721112Y854419D03*
X724093Y840187D03*
X726776Y842277D03*
X733796Y854172D03*
G54D30*
X53540Y212898D03*
G54D40*
X60983Y392640D03*
Y389240D03*
X63585Y496598D03*
X120763Y228683D03*
X110063Y228783D03*
X109736Y306270D03*
X91863Y382983D03*
X106257Y409989D03*
X91752Y379460D03*
X95400Y455100D03*
X110863Y430483D03*
X115063Y448583D03*
X118880Y465509D03*
X132163Y441583D03*
X118813Y461961D03*
X118794Y458462D03*
X150563Y228783D03*
X150763Y305503D03*
X172478Y473409D03*
X171943Y469870D03*
X149899Y461877D03*
X679465Y467377D03*
Y463877D03*
X681909Y453623D03*
X679684Y546217D03*
X714291Y564572D03*
G54D31*
X63444Y266211D03*
X38892Y293747D03*
X130163Y413483D03*
X137163Y434483D03*
X129768Y422719D03*
X434994Y457361D03*
X435016Y449543D03*
G54D13*
X4800Y48600D03*
X5800Y6400D03*
X5000Y71900D03*
Y91900D03*
X5100Y111800D03*
X4900Y130400D03*
X5000Y150500D03*
X5300Y170000D03*
X9151Y473051D03*
X8672Y487593D03*
X7075Y527972D03*
X7927Y509647D03*
X8140Y637282D03*
X8246Y771416D03*
X45700Y61000D03*
X65500Y60800D03*
X75500D03*
X45900Y50000D03*
X65700Y49800D03*
X50800Y39500D03*
X70700Y45800D03*
X55800Y61300D03*
X59900Y40600D03*
X53200Y26300D03*
X50600Y6000D03*
X50500Y67700D03*
X70500Y72000D03*
X60800Y72500D03*
X76800Y99900D03*
X57200Y175300D03*
X63700Y194818D03*
X71100Y181200D03*
X69100Y195200D03*
X47100Y267600D03*
X67800Y250100D03*
X67039Y272085D03*
X70415Y260333D03*
X70188Y224633D03*
X40500Y227100D03*
X14200Y339400D03*
X45215Y283633D03*
X25700Y306400D03*
X70118Y287233D03*
X30700Y306300D03*
X70015Y294733D03*
X70238Y279733D03*
X33722Y394233D03*
X18115Y413228D03*
X20915Y348544D03*
X39244Y411695D03*
X46741Y411938D03*
X27715Y410133D03*
X22646Y397233D03*
X16415Y361841D03*
X73100Y380933D03*
X59215Y375233D03*
X18915Y449033D03*
X34334Y438445D03*
X22315Y441743D03*
X38115Y445328D03*
X31134Y449532D03*
X51425Y453027D03*
X16158Y477255D03*
X39600Y494800D03*
X38200Y490900D03*
X35100Y494400D03*
X33600Y512600D03*
X37329Y524472D03*
X33880Y526500D03*
X33921Y520414D03*
X64700Y506200D03*
X18809Y491871D03*
X17212Y532250D03*
X18064Y513925D03*
X75702Y536228D03*
X69200Y531100D03*
X70115Y541233D03*
X70900Y519700D03*
X18277Y641560D03*
X9844Y658803D03*
X19981Y663081D03*
X39353Y708533D03*
X9631Y753837D03*
X19768Y758115D03*
X18383Y775694D03*
X55459Y780063D03*
X48300Y775300D03*
X87900Y47800D03*
X90900Y42400D03*
X80400Y47800D03*
X124100Y6700D03*
X110800Y48800D03*
X120200Y48400D03*
X98700Y48900D03*
X143900Y38000D03*
X108100Y35300D03*
X146900Y48500D03*
X109700Y6400D03*
X119700Y35400D03*
X139800Y31100D03*
X96300Y6100D03*
X147200Y7300D03*
X108600Y19900D03*
X126500Y20100D03*
X92600Y79800D03*
X147500Y90200D03*
X142167Y106366D03*
X142101Y98650D03*
X146015Y79433D03*
X111100Y75500D03*
X100000Y75600D03*
X121700Y75300D03*
X85300Y70200D03*
X83800Y188800D03*
X111482Y202800D03*
X126300Y180209D03*
X126700Y173500D03*
X136291Y179968D03*
X136100Y173800D03*
X113815Y194333D03*
X122400Y199000D03*
X98968Y194794D03*
X115115Y166600D03*
X89300Y144600D03*
X125600Y228985D03*
X87200Y222000D03*
X134200Y217300D03*
X130000Y217200D03*
X134600Y222200D03*
X98715Y313833D03*
X87115Y331571D03*
X119615Y312033D03*
X84958Y305933D03*
X100315Y305033D03*
X141315Y305433D03*
X97000Y389200D03*
X90815Y445833D03*
X90501Y480516D03*
X98286Y465448D03*
X125853Y473129D03*
X89400Y659100D03*
X80200Y633900D03*
X83500Y653600D03*
Y640044D03*
X84900Y747900D03*
X106051Y767209D03*
X85300Y755100D03*
X85000Y775900D03*
X122899Y825236D03*
X112762Y820958D03*
X116188Y771487D03*
X84100Y769000D03*
X131900Y893200D03*
X120874Y857517D03*
X110737Y853239D03*
X131700Y915700D03*
X89871Y917500D03*
X209100Y51700D03*
X191700Y63300D03*
X209200Y65100D03*
X200700Y51700D03*
X185100Y55900D03*
X208900Y58600D03*
X192000Y55900D03*
X200700Y58300D03*
X184700Y63100D03*
X173200Y10900D03*
X213700Y35200D03*
X186000D03*
X197796Y12653D03*
X160600Y49100D03*
X153200Y48700D03*
X167500Y49000D03*
X160500Y19700D03*
X170400Y31100D03*
X150600Y37800D03*
X197900Y82000D03*
X154500Y90000D03*
X158000Y79600D03*
X165200Y79500D03*
X163300Y95900D03*
X163500Y105500D03*
X151800Y72400D03*
X216415Y108238D03*
X208115Y95933D03*
X186615Y83733D03*
X209000Y72300D03*
X201500D03*
X177100Y99500D03*
X177200Y104800D03*
X177300Y94200D03*
Y88500D03*
X184700D03*
X190700Y77800D03*
X201200Y65600D03*
X191000Y71300D03*
X184500Y71200D03*
X177400Y71400D03*
X177500Y77900D03*
X183700Y78100D03*
X191500Y88500D03*
X201614Y89932D03*
X204200Y126700D03*
X206600Y130300D03*
X201900D03*
X152400Y124300D03*
X170302Y147100D03*
X158100Y166800D03*
X207495Y192761D03*
X169800Y155796D03*
X165162Y155909D03*
X169709Y160049D03*
X165388Y160094D03*
X167015Y167633D03*
X163550Y179657D03*
X151615Y176111D03*
X188590Y262541D03*
X176915Y255433D03*
X188115Y253008D03*
X169800Y274100D03*
X169715Y250448D03*
X168115Y308933D03*
X187615Y289433D03*
X170800Y297900D03*
X191615Y282933D03*
X177215Y279133D03*
X156515Y305233D03*
X170315Y284833D03*
X170596Y292689D03*
X219728Y457397D03*
X197885Y436402D03*
X181400Y485900D03*
X205881Y441150D03*
X199315Y447233D03*
X206917Y435857D03*
X212300Y439300D03*
X209000Y447500D03*
X205400Y462100D03*
X196400Y585300D03*
X179000Y624800D03*
X193600Y702400D03*
X179100Y714600D03*
X202300Y742000D03*
X189273Y902478D03*
X213138Y905780D03*
X218729Y857629D03*
X200460Y913771D03*
X282282Y47189D03*
X286930D03*
X233900Y32500D03*
X252187Y23895D03*
X286651Y14571D03*
X224431Y15210D03*
X248900Y8400D03*
X241817Y72536D03*
X282444Y106834D03*
X225919Y88394D03*
X225937Y80731D03*
X221710Y80767D03*
X221722Y88431D03*
X230158Y88359D03*
X230123Y80805D03*
X225851Y73774D03*
X221740Y73844D03*
X229870Y73970D03*
X228169Y68374D03*
X224169Y68520D03*
X228728Y96613D03*
X224285Y96750D03*
X242488Y88466D03*
X258741Y193852D03*
X256823Y221979D03*
X246169Y246270D03*
X230774Y270268D03*
X241694Y274956D03*
X228635Y385956D03*
X232788Y385893D03*
X279629Y405032D03*
X257015Y394833D03*
X249300Y398800D03*
X251100Y408500D03*
X244600Y485200D03*
X290615Y432406D03*
X267673Y429991D03*
X237576Y417080D03*
X253615Y428333D03*
X245000Y432000D03*
X258100Y452100D03*
X241565Y437435D03*
X253500Y458500D03*
X241300Y449000D03*
X221800Y436500D03*
X237980Y467226D03*
X240400Y423600D03*
X224015Y427633D03*
X267479Y420536D03*
X226000Y447700D03*
X233900Y455700D03*
X223500Y469900D03*
X228800Y481300D03*
X224700Y462200D03*
X243300Y464500D03*
X226818Y439263D03*
X229764Y513034D03*
X234416Y512963D03*
X238924Y512390D03*
X243100Y516300D03*
X245963Y511890D03*
X250975Y511729D03*
X255500Y514000D03*
X264000Y513400D03*
X277300Y572500D03*
X259600Y568400D03*
X271949Y648699D03*
X272588Y681087D03*
X244248Y682153D03*
X255542Y665532D03*
X241904Y652321D03*
X289634Y659352D03*
X284520Y743307D03*
X282176Y713475D03*
X230823Y823850D03*
X253623Y867319D03*
X254262Y899707D03*
X225922Y900773D03*
X237216Y884152D03*
X223578Y870941D03*
X285585Y897363D03*
X283241Y867531D03*
X264212Y903112D03*
X299300Y41300D03*
X321300Y43200D03*
X351800Y42200D03*
X360500Y42600D03*
X330000Y42800D03*
X329900Y37100D03*
X321300D03*
X360500Y36700D03*
X291373Y47394D03*
X299300Y46400D03*
X351800Y36300D03*
X299600Y62100D03*
X351900Y62000D03*
X360200Y62300D03*
X329500Y62600D03*
X321300Y63100D03*
X325006Y15636D03*
X299500Y68200D03*
X352000Y68000D03*
X360200Y68200D03*
X329600D03*
X321400Y68500D03*
X344663Y108965D03*
X312275Y98098D03*
X354197Y158187D03*
X301140Y161383D03*
X352066Y262596D03*
X307320Y223390D03*
X301781Y258122D03*
X322022Y279856D03*
X291453Y414238D03*
X299330Y417148D03*
X356380Y476847D03*
X320207Y428442D03*
X320166Y432442D03*
X309648Y582024D03*
X319679Y655730D03*
X320318Y688118D03*
X291978Y689184D03*
X303272Y672563D03*
X347378Y688332D03*
X358672Y671711D03*
X345034Y658500D03*
X302115Y693462D03*
X360803Y704312D03*
X333102Y737766D03*
X344396Y721145D03*
X330758Y707934D03*
X312221Y709853D03*
X312860Y742241D03*
X295814Y726686D03*
X319171Y767846D03*
X313959Y724732D03*
X354623Y896937D03*
X352279Y867105D03*
X313286Y863909D03*
X313925Y896297D03*
X296879Y880742D03*
X332436Y858576D03*
X337648Y901690D03*
X382100Y61900D03*
X401343Y58465D03*
X394098Y20059D03*
X362775D03*
X412506Y33484D03*
X382200Y68500D03*
X410025Y87658D03*
X390208Y180135D03*
X366982Y198886D03*
X407769Y204757D03*
X384668Y247681D03*
X376144Y279856D03*
X380956Y408290D03*
X376513Y408085D03*
X371865D03*
X380392Y416962D03*
X375949Y416757D03*
X371301D03*
X366653Y416484D03*
X367217Y407812D03*
X426700Y475000D03*
X423746Y470900D03*
X366719Y424200D03*
X371367Y424473D03*
X376015D03*
X380458Y424678D03*
X414894Y453432D03*
X419296Y449111D03*
X423572Y453454D03*
X419092Y457572D03*
X419225Y453324D03*
X410015Y479733D03*
X410200Y474200D03*
X410179Y469769D03*
X400515Y433533D03*
X375079Y654878D03*
X375718Y687266D03*
X430267Y679595D03*
X413860Y696428D03*
X400222Y683217D03*
X388817Y692040D03*
X420252Y725194D03*
X420891Y757582D03*
X392551Y758648D03*
X403845Y742027D03*
X390207Y728816D03*
X361442Y736700D03*
X430906Y711983D03*
X402566Y713049D03*
X395450Y767846D03*
X378868Y723311D03*
X421530Y814262D03*
X419186Y784430D03*
X429202Y894806D03*
X426858Y864974D03*
X382324Y863483D03*
X382963Y895871D03*
X365917Y880316D03*
X413927Y901690D03*
X397345Y857155D03*
X432682Y23909D03*
X472315Y23056D03*
X496393Y55871D03*
X457399Y46069D03*
X496109Y93412D03*
X457989Y78967D03*
X493200Y145500D03*
X451789Y154565D03*
X473097Y208901D03*
X453252Y250240D03*
X440715Y444133D03*
X438300Y481200D03*
X434515Y483333D03*
X434412Y479334D03*
X432014Y476132D03*
X440815Y458633D03*
X434515Y436133D03*
X493050Y486350D03*
X444115Y490049D03*
X498794Y493300D03*
X500894Y499600D03*
X455846Y546626D03*
X489000Y493700D03*
X465212Y726260D03*
X465851Y758648D03*
X437511Y759714D03*
X448805Y743093D03*
X435167Y729882D03*
X474587Y765253D03*
X445197Y719047D03*
X449231Y780808D03*
X449870Y813196D03*
X432824Y797641D03*
X476931Y795085D03*
X488225Y778464D03*
X499945Y828325D03*
X486307Y815114D03*
X456903Y861352D03*
X457542Y893740D03*
X440496Y878185D03*
X488651Y844946D03*
X499208Y899795D03*
X463674Y852891D03*
X557547Y24335D03*
X526213Y34431D03*
X555558Y100229D03*
X531425Y77545D03*
X545330Y147959D03*
X521476Y205704D03*
X509632Y174434D03*
X526688Y248818D03*
X503300Y539700D03*
X566000Y536700D03*
X508224Y580873D03*
X549379Y653173D03*
X504632Y761631D03*
X505271Y794019D03*
X516352Y811492D03*
X562377Y833013D03*
X532332Y836635D03*
X516991Y843880D03*
X563016Y865401D03*
X534676Y866467D03*
X545970Y849846D03*
X545118Y880530D03*
X528711Y897363D03*
X515073Y884152D03*
X562590Y881808D03*
X510579Y854786D03*
X545757Y912918D03*
X517417Y913984D03*
X564934Y911640D03*
X573457Y59531D03*
X621826Y20111D03*
X591122Y33010D03*
X607704Y77545D03*
X586385Y204283D03*
X596334Y173012D03*
X602967Y248818D03*
X633923Y520400D03*
X634700Y544300D03*
X640900Y546800D03*
X639200Y540600D03*
X639900Y554500D03*
X587942Y582024D03*
X626700Y586700D03*
X614582Y653599D03*
X604141Y675547D03*
X578784Y682152D03*
X582620Y653386D03*
X632693Y697281D03*
X607550Y703460D03*
X628006Y720720D03*
X592635Y878186D03*
X576228Y895019D03*
X640791Y876268D03*
X641430Y908656D03*
X613090Y909722D03*
X624384Y893101D03*
X610746Y879890D03*
X593274Y910574D03*
X660180Y56547D03*
X657451Y28746D03*
X703700Y30300D03*
X651658Y95968D03*
X692985Y75650D03*
X699619Y201914D03*
X652714Y200019D03*
X692512Y162589D03*
X661673Y260892D03*
X688248Y246923D03*
X712386Y297542D03*
X711500Y438300D03*
X688409Y442578D03*
X693409Y442656D03*
X703400Y442200D03*
X698404Y442423D03*
X694995Y453626D03*
X694923Y461253D03*
X694851Y469456D03*
X694907Y476993D03*
X675415Y437533D03*
X683409Y442604D03*
X708300Y480600D03*
X707900Y485800D03*
X644900Y538300D03*
X689200Y511600D03*
X673100Y535400D03*
X711500Y490200D03*
X680800Y542100D03*
X668135Y523360D03*
X672161Y528021D03*
X676550Y523677D03*
X672342Y519560D03*
X672257Y523769D03*
X685800Y549900D03*
X677815Y493833D03*
X706695Y559800D03*
X680700Y558000D03*
X688600Y557800D03*
X649500Y564300D03*
X680300Y584400D03*
X678293Y698772D03*
X675736Y657222D03*
X694061Y681726D03*
X654641Y691101D03*
X643987Y664041D03*
X697897Y662763D03*
X704215Y762804D03*
X712215Y766571D03*
X708231Y730948D03*
X681276Y722211D03*
X650805Y716671D03*
X698962Y707936D03*
X684515Y760867D03*
X703515Y771013D03*
X711815Y775149D03*
X703415Y779285D03*
X704215Y787599D03*
Y799456D03*
X704015Y834000D03*
X680706Y781109D03*
X687848Y783400D03*
X686672Y793470D03*
X685389Y802213D03*
X705215Y824663D03*
X692356Y875629D03*
X692995Y908017D03*
X664655Y909083D03*
X675949Y892462D03*
X662311Y879251D03*
X703515Y842302D03*
X711415Y846395D03*
X703415Y850609D03*
X754800Y56800D03*
Y36800D03*
Y16800D03*
X723466Y60810D03*
X721334Y17767D03*
X754800Y76800D03*
X754700Y117600D03*
Y97600D03*
X734333Y88085D03*
X754700Y197600D03*
Y177600D03*
Y157600D03*
Y137600D03*
Y257600D03*
Y237600D03*
Y217600D03*
Y277600D03*
X753800Y303200D03*
X767300Y340400D03*
X766900Y333754D03*
X735134Y289819D03*
X767000Y410900D03*
X766700Y403500D03*
X766900Y395400D03*
Y387800D03*
Y364600D03*
Y356300D03*
X767600Y348500D03*
X767400Y481600D03*
Y465900D03*
X767500Y450800D03*
X767300Y441747D03*
X766500Y435100D03*
X766800Y427000D03*
X767100Y418700D03*
X754457Y530156D03*
X747015Y518472D03*
X759115Y524233D03*
X761015Y536033D03*
X739385Y553915D03*
X728300Y531200D03*
X767100Y544600D03*
X766800Y535700D03*
X767200Y524500D03*
X766900Y497700D03*
X767200Y489700D03*
X756433Y503965D03*
X754615Y511733D03*
X746300Y504900D03*
X761355Y516454D03*
X761900Y508300D03*
X756900Y554700D03*
X761000Y551800D03*
X742400Y559900D03*
X767100Y623900D03*
Y614800D03*
X766700Y606900D03*
X767700Y600200D03*
X766700Y592700D03*
X767000Y584300D03*
Y576100D03*
Y569500D03*
X736176Y583406D03*
X761400Y560500D03*
X756900Y563300D03*
X748900Y644700D03*
X726000Y650700D03*
X720000Y650800D03*
X733000Y650600D03*
X740000D03*
X766900Y639500D03*
Y631900D03*
X715795Y697494D03*
X750300Y663000D03*
X740513Y687906D03*
X755115Y740179D03*
X745733Y713048D03*
X744615Y759864D03*
X764200Y813000D03*
X713015Y783400D03*
X715515Y791967D03*
X713915Y802017D03*
X713715Y829925D03*
X713015Y838158D03*
X744700Y828200D03*
X742336Y838933D03*
X731615Y846447D03*
X726013Y855385D03*
X745413Y854763D03*
X716221Y876694D03*
X729859Y889905D03*
X718565Y906526D03*
X746905Y905460D03*
X746266Y873072D03*
X716539Y852514D03*
G54D22*
X74800Y91200D03*
X43851Y182228D03*
X43794Y197158D03*
X22900Y313600D03*
X39236Y283887D03*
X27000Y313500D03*
X31100D03*
X63942Y537679D03*
X67065Y519137D03*
X98138Y405678D03*
X89163Y390283D03*
X94076Y414654D03*
X118163Y474383D03*
X149799Y452326D03*
X428616Y437029D03*
X684869Y438211D03*
X680738Y438233D03*
X693509Y438301D03*
X689111Y438212D03*
X705600Y554600D03*
X663300Y529600D03*
X648200Y555500D03*
X705927Y532127D03*
X668699Y556030D03*
X726040Y550596D03*
G54D41*
X57383Y392640D03*
Y389240D03*
X59985Y496598D03*
X146963Y228783D03*
X117163Y228683D03*
X106463Y228783D03*
X106136Y306270D03*
X147163Y305503D03*
X88263Y382983D03*
X102657Y409989D03*
X88152Y379460D03*
X91800Y455100D03*
X107263Y430483D03*
X111463Y448583D03*
X115280Y465509D03*
X128563Y441583D03*
X146299Y461877D03*
X115213Y461961D03*
X115194Y458462D03*
X168878Y473409D03*
X168343Y469870D03*
X675865Y467377D03*
Y463877D03*
X678309Y453623D03*
X676084Y546217D03*
X710691Y564572D03*
G54D50*
X102363Y449283D03*
X125579Y421573D03*
X701500Y518600D03*
X680800D03*
G54D32*
X63444Y262611D03*
X38892Y290147D03*
X130163Y409883D03*
X137163Y430883D03*
X129768Y419119D03*
X434994Y453761D03*
X435016Y445943D03*
G54D23*
X43848Y189691D03*
X30773Y274407D03*
X35107Y274462D03*
X67367Y526739D03*
X63918Y545213D03*
X113749Y313569D03*
X93263Y390283D03*
X107363Y450183D03*
X94500Y465600D03*
X91167Y491594D03*
X181278Y247657D03*
X424282Y437118D03*
X707109Y438423D03*
X698367Y438402D03*
X702508Y438404D03*
X705600Y547000D03*
X663300Y522000D03*
X648200Y548000D03*
X705928Y524645D03*
X668705Y548544D03*
X685815Y493278D03*
X689996Y493247D03*
X698475Y493274D03*
X694196Y493347D03*
X707296D03*
X702648Y493237D03*
X668743Y541065D03*
X726045Y543153D03*
G54D14*
G01X-771361Y-182763D02*
Y-262763D01*
G01Y-218263D02*
X373639D01*
G01X-771361Y-262763D02*
X373639D01*
G01X-775361Y-166763D02*
G02I-12000J0D01*
G01X-780511D02*
G02I-6850J0D01*
G01X-787361Y-182763D02*
Y-150763D01*
G01X-771361Y-166763D02*
X-803361D01*
G01X-771361Y-182763D02*
X373639D01*
G01X-413861D02*
Y-262763D01*
G01X-276361Y-182763D02*
Y-262763D01*
G01X-161361Y-182763D02*
Y-262763D01*
G01X6139Y-182763D02*
Y-262763D01*
G01X55700Y87650D02*
X59271D01*
X59274Y87653D01*
G01D02*
X61753D01*
X63400Y89300D01*
G01X59274Y91153D02*
Y95499D01*
X59200Y95573D01*
G01X55700Y91150D02*
X59271D01*
X59274Y91153D01*
G01X43848Y186241D02*
X32041D01*
X31500Y185700D01*
G01X58080Y181464D02*
X61751D01*
G01X49286Y203671D02*
Y203257D01*
X49009Y202980D01*
Y199321D01*
G01X43794Y197208D02*
Y200294D01*
X44100Y200600D01*
G01X76107Y138611D02*
X77461Y139965D01*
X80207D01*
G01X39800Y172900D02*
X42195Y175295D01*
X48905D01*
X56951Y167249D01*
X70004D01*
X85713Y151540D01*
G01X60150Y251200D02*
Y254936D01*
X60009Y255077D01*
G01X33400Y266400D02*
X35107Y268107D01*
Y271012D01*
G01X30773Y270957D02*
Y269027D01*
X33400Y266400D01*
G01X65808Y211203D02*
Y213992D01*
X64700Y215100D01*
G01X53740Y212898D02*
Y214860D01*
X51600Y217000D01*
G01X38892Y293697D02*
Y303126D01*
X35230Y306788D01*
G01X42507Y296616D02*
Y295297D01*
X40907Y293697D01*
X38892D01*
G01X59316Y300366D02*
X66014Y307064D01*
X75876D01*
G01X22900Y313650D02*
X19050D01*
X17100Y311700D01*
G01X39236Y280437D02*
X41347D01*
X43181Y278603D01*
G01X38892Y290197D02*
X40303D01*
X41418Y289082D01*
Y287473D01*
G01X35230Y310288D02*
X35231Y310287D01*
X37244D01*
X39563Y307968D01*
G01X53547Y302486D02*
X65725Y314664D01*
X75876D01*
G01X57433Y381140D02*
X56215Y379922D01*
Y372755D01*
X61776Y367194D01*
G01X63413Y488486D02*
Y488683D01*
G01X43500Y534400D02*
X40100D01*
X38800Y535700D01*
G01X43423Y528179D02*
X42702Y528900D01*
X38200D01*
G01X63535Y496598D02*
Y500390D01*
X63177Y500748D01*
G01X63413Y488683D02*
Y493878D01*
X63535Y494000D01*
Y496598D01*
G01X32026Y516764D02*
X37614D01*
X43106Y511272D01*
X44879D01*
G01X64700Y506200D02*
X64600Y506300D01*
X61900D01*
X60800Y505200D01*
G01D02*
Y504371D01*
X57177Y500748D01*
G01D02*
X56395Y499966D01*
X50799D01*
G01X60035Y496598D02*
X58448D01*
X56121Y494271D01*
G01X50799Y492366D02*
X54216D01*
X56121Y494271D01*
G01X50893Y534434D02*
X52732Y536273D01*
X57065D01*
G01X63918Y545263D02*
Y545618D01*
X66300Y548000D01*
G01X54570Y530394D02*
X57065Y532889D01*
Y536273D01*
G01X47000Y645300D02*
X46700Y645600D01*
Y662400D01*
X39200Y669900D01*
Y708380D01*
X39353Y708533D01*
G01X47100Y746000D02*
X39353Y738253D01*
Y708533D01*
G01X132500Y124600D02*
X132800Y124300D01*
X152400D01*
G01X79750Y144900D02*
Y148550D01*
X79900Y148700D01*
G01X144950Y177338D02*
X146177Y176111D01*
X151615D01*
G01X125700Y225200D02*
X127750D01*
X131150Y228600D01*
G01X121000Y225300D02*
X120713Y225587D01*
Y228683D01*
G01X109400Y225400D02*
X110013Y226013D01*
Y228783D01*
G01X83050Y225900D02*
X79800D01*
G01X147013Y225483D02*
Y228783D01*
G01X97885Y228339D02*
X97441Y228783D01*
X94313D01*
G01X102559Y228575D02*
X102767Y228783D01*
X106513D01*
G01X113863Y228669D02*
X113877Y228683D01*
X117213D01*
G01X125600Y221200D02*
X128700D01*
X134650Y227150D01*
Y228600D01*
G01X109534Y314564D02*
X109686Y314412D01*
Y306270D01*
G01X98715Y313833D02*
X93060D01*
X89862Y310635D01*
Y306463D01*
X90869Y305456D01*
G01X109534Y314564D02*
X108803Y313833D01*
X98715D01*
G01X113749Y313619D02*
X113985D01*
X115339Y314973D01*
X121477D01*
G01X135613Y308903D02*
Y305703D01*
X135513Y305603D01*
G01X147213Y305503D02*
Y306887D01*
X145167Y308933D01*
X135643D01*
X135613Y308903D01*
G01X94076Y414704D02*
Y417942D01*
X94263Y418129D01*
G01X91813Y382983D02*
X95300D01*
X95400Y383083D01*
G01D02*
Y385865D01*
X94432Y386833D01*
X93263D01*
G01X91702Y379460D02*
X91813Y379571D01*
Y382983D01*
G01X106207Y409989D02*
Y412922D01*
X106855Y413570D01*
G01X102707Y409989D02*
X99963D01*
X99791Y410161D01*
X98427D01*
G01X114175Y414098D02*
X113647Y413570D01*
X110355D01*
G01X88313Y382983D02*
X89163Y383833D01*
Y386833D01*
G01X84200Y380000D02*
X87662D01*
X88202Y379460D01*
G01X129768Y422669D02*
X130809D01*
X133953Y425813D01*
G01X125579Y427373D02*
Y429917D01*
X127033Y431371D01*
G01X118763Y461961D02*
X123952D01*
X126310Y459603D01*
G01X118763Y461961D02*
Y458481D01*
X118744Y458462D01*
G01X118830Y465509D02*
Y462028D01*
X118763Y461961D01*
G01X127033Y431371D02*
Y434871D01*
G01D02*
Y436677D01*
X125990Y437720D01*
G01X95350Y455100D02*
X96406D01*
X98597Y457291D01*
G01X129768Y419169D02*
X128895Y418296D01*
X126252D01*
X126180Y418224D01*
G01X115244Y458462D02*
Y461942D01*
X115263Y461961D01*
G01X91850Y455100D02*
X91200Y455750D01*
Y461066D01*
X90662Y461604D01*
G01X129927Y437720D02*
X130533Y437114D01*
Y434871D01*
G01X126180Y418224D02*
X125579Y418825D01*
Y421373D01*
G01X106449Y465157D02*
X105909Y465697D01*
X102643D01*
G01X115263Y461961D02*
Y465442D01*
X115330Y465509D01*
G01X130533Y434871D02*
Y431371D01*
G01X115330Y465509D02*
X115006Y465833D01*
X111681D01*
X111631Y465783D01*
X107075D01*
X106449Y465157D01*
G01X176139Y-182763D02*
Y-262763D01*
G01X152400Y124300D02*
X179400D01*
X200100Y103600D01*
Y101200D01*
G01X177087Y178920D02*
X176966D01*
X174157Y176111D01*
X151615D01*
G01X177150Y273900D02*
X181151D01*
X183082Y271969D01*
G01X154300Y227900D02*
X153417Y228783D01*
X150513D01*
G01X177165Y244229D02*
X181256D01*
X181278Y244207D01*
G01X175064Y232857D02*
Y235731D01*
X172508Y238287D01*
G01X171200Y233000D02*
Y237147D01*
X172340Y238287D01*
X172508D01*
G01X180108D02*
X180641Y237754D01*
Y231683D01*
G01X174605Y265687D02*
X175246Y266328D01*
Y269694D01*
G01D02*
X180831D01*
X181757Y268768D01*
X185627D01*
X186319Y268076D01*
G01X183707Y289861D02*
X183837D01*
X186666Y292690D01*
Y295344D01*
X182204Y299806D01*
X177242D01*
X168115Y308933D01*
G01D02*
X154143D01*
X150713Y305503D01*
G01X183466Y294017D02*
X180014D01*
G01X172428Y473409D02*
Y474364D01*
X170683Y476109D01*
X170282D01*
X169297Y477094D01*
G01X171893Y469870D02*
X172428Y470405D01*
Y473409D01*
G01X169297Y465283D02*
X171893Y467879D01*
Y469870D01*
G01X168319Y432425D02*
Y431350D01*
X168711Y430958D01*
Y430134D01*
X169166Y429679D01*
G01X171819Y432425D02*
Y431893D01*
X174351Y429361D01*
Y429014D01*
G01X168393Y469870D02*
X166010D01*
X165360Y469220D01*
G01X168928Y473409D02*
X168393Y472874D01*
Y469870D01*
G01X241101Y81230D02*
X261830D01*
G01X241132Y85023D02*
X240367D01*
X237901Y82557D01*
Y76452D01*
X241817Y72536D01*
G01X256928Y69301D02*
X245052D01*
X241817Y72536D01*
G01X304783Y467192D02*
X289391Y451800D01*
X287922D01*
X285734Y449612D01*
Y443377D01*
X258909Y416552D01*
X251652D01*
X243300Y408200D01*
X237841D01*
X234582Y404941D01*
X224932D01*
X222269Y402278D01*
G01X335532Y485626D02*
X342421D01*
X346865Y490070D01*
X422072D01*
X422093Y490049D01*
X444115D01*
G01X373639Y-182763D02*
Y-262763D01*
G01X401639Y-166763D02*
G02I-12000J0D01*
G01X396489D02*
G02I-6850J0D01*
G01X389639Y-182763D02*
Y-150763D01*
G01X405639Y-166763D02*
X373639D01*
G01X424343Y463067D02*
X428343D01*
G01X428616Y433579D02*
Y429466D01*
G01X399900Y458600D02*
X400934Y457566D01*
Y453986D01*
G01X391500Y459000D02*
Y455639D01*
X393110Y454029D01*
G01X416588Y471346D02*
Y467839D01*
G01X416582Y475470D02*
Y480472D01*
X418076Y481966D01*
G01X434994Y457311D02*
X439193D01*
X440515Y458633D01*
G01D02*
X440815D01*
G01X435138Y460661D02*
X435166Y460633D01*
X438515D01*
X440515Y458633D01*
G01X438294Y453811D02*
X434994D01*
G01X435016Y449493D02*
X438316D01*
G01X471410Y490049D02*
X444115D01*
G01X663300Y518550D02*
X647650D01*
X630200Y536000D01*
X629100D01*
G01X678359Y453623D02*
Y447544D01*
X678767Y447136D01*
G01X711559Y453723D02*
X710709Y452873D01*
Y451901D01*
X710645Y451837D01*
Y447266D01*
G01X711480Y464221D02*
X711380Y467573D01*
X711409Y467602D01*
Y467621D01*
G01X682774Y449737D02*
X681859Y450652D01*
Y453623D01*
G01X708059Y453723D02*
Y449951D01*
G01X668699Y556080D02*
Y559099D01*
X669200Y559600D01*
G01X705928Y521195D02*
X707505D01*
X710400Y518300D01*
X715125D01*
X716300Y517125D01*
G01X668705Y545094D02*
X669954D01*
X671915Y543133D01*
G01X668743Y541115D02*
X669897D01*
X671915Y543133D01*
G01X689850Y545500D02*
X692050Y547700D01*
X694700D01*
G01X705600Y554650D02*
X703050D01*
X702900Y554800D01*
X702400D01*
G01X705927Y532177D02*
Y538650D01*
G01D02*
X705600Y538977D01*
Y543550D01*
G01X663300Y529650D02*
Y535095D01*
X663600Y535395D01*
G01X648200Y555550D02*
X645750D01*
X644600Y556700D01*
G01X652400Y545200D02*
X651000D01*
X650350Y544550D01*
X648200D01*
G01X644900Y538300D02*
Y538100D01*
X646150Y536850D01*
X648500D01*
G01D02*
Y536000D01*
X651100Y533400D01*
X653750D01*
G01X696850Y511400D02*
X699316D01*
X700512Y510204D01*
G01X684600Y542100D02*
X680800D01*
G01X679634Y546217D02*
Y543266D01*
X680800Y542100D01*
G01X700900Y539500D02*
X701800Y538600D01*
Y535300D01*
X701500Y535000D01*
G01X685815Y493328D02*
Y496140D01*
G01X689996Y493297D02*
Y496274D01*
G01X698475Y493324D02*
Y496387D01*
G01X707296Y493397D02*
Y496348D01*
G01X702648Y493287D02*
Y496126D01*
X702670Y496148D01*
G01X694196Y493397D02*
Y496367D01*
X694169Y496394D01*
G01X676134Y546217D02*
Y542652D01*
X676115Y542633D01*
G01X672342Y519560D02*
X673502Y518400D01*
X680800D01*
G01X657250Y533400D02*
Y527761D01*
X658314Y526697D01*
G01X648500Y540350D02*
X651745D01*
X651800Y540295D01*
G01X680800Y535000D02*
Y537200D01*
X676115Y541885D01*
Y542633D01*
G01X701500Y518400D02*
X701700Y518200D01*
X704789D01*
X707589Y515400D01*
G01X681300Y513950D02*
Y517900D01*
X680800Y518400D01*
G01X681300Y513950D02*
X677800D01*
G01X656817Y563931D02*
Y567131D01*
G01X710741Y564572D02*
X708421D01*
X708415Y564566D01*
X707391D01*
G01X766900Y333754D02*
X769924Y330730D01*
X779564D01*
G01X767300Y340400D02*
X769440Y342540D01*
X781514D01*
G01X767600Y348500D02*
X769620Y346480D01*
X781514D01*
G01X766900Y356300D02*
X768890Y358290D01*
X781514D01*
G01X766900Y364600D02*
X769275Y362225D01*
X781514D01*
G01X766900Y387800D02*
X768850Y385850D01*
X781514D01*
G01X766900Y395400D02*
X769160Y397660D01*
X781514D01*
G01X766700Y403500D02*
X768605Y401595D01*
X781514D01*
G01X767000Y410900D02*
X769505Y413405D01*
X781514D01*
G01X767700Y473300D02*
X770800Y476400D01*
X781514D01*
G01X767100Y418700D02*
X768455Y417345D01*
X781514D01*
G01X766800Y427000D02*
X768955Y429155D01*
X781514D01*
G01X766500Y435100D02*
X768510Y433090D01*
X781514D01*
G01X767400Y465900D02*
X768710Y464590D01*
X781514D01*
G01X767400Y481600D02*
X768665Y480335D01*
X781514D01*
G01X715695Y480900D02*
X717100D01*
X719100Y478900D01*
G01X715695Y485000D02*
X716295Y485600D01*
X719700D01*
G01X781514Y444905D02*
X770458D01*
G01X781514Y448840D02*
X769460D01*
G01X770458Y444905D02*
X767300Y441747D01*
G01X769460Y448840D02*
X767500Y450800D01*
G01X726040Y550646D02*
X728846D01*
X729700Y551500D01*
G01D02*
Y552879D01*
X727942Y554637D01*
X725784D01*
G01X730350Y535700D02*
Y539650D01*
X729600Y540400D01*
G01X726045Y539703D02*
X727624D01*
X728321Y540400D01*
X729600D01*
G01X767200Y489700D02*
X769645Y492145D01*
X781514D01*
G01X766800Y535700D02*
X767045Y535455D01*
X781514D01*
G01X767100Y544600D02*
X769765Y547265D01*
X781514D01*
G01X714241Y564572D02*
X714276Y564537D01*
Y560695D01*
G01X717879Y564572D02*
X714241D01*
G01X767000Y569500D02*
X769550Y566950D01*
X781514D01*
G01X767000Y576100D02*
X769660Y578760D01*
X781514D01*
G01X767000Y584300D02*
X768600Y582700D01*
X781514D01*
G01X766700Y592700D02*
X768510Y594510D01*
X781514D01*
G01X767700Y600200D02*
X769455Y598445D01*
X781514D01*
G01X766700Y606900D02*
X770060Y610260D01*
X781514D01*
G01X767100Y614800D02*
X767705Y614195D01*
X781514D01*
G01X767100Y623900D02*
X769205Y626005D01*
X781514D01*
G01X725784Y558137D02*
X725900Y558253D01*
Y561800D01*
G01X766300Y655800D02*
X768000Y657500D01*
X781514D01*
G01X766200Y653900D02*
X766535Y653565D01*
G01X766300Y651000D02*
X767670Y649630D01*
G01D02*
X781514D01*
G01X766535Y653565D02*
X781514D01*
G01X766900Y631900D02*
X768855Y629945D01*
X781514D01*
G01X766900Y639500D02*
X769155Y641755D01*
X781514D01*
G01X741713Y855068D02*
X745108D01*
X745413Y854763D01*
G01X741550Y859500D02*
X745005D01*
X745100Y859405D01*
X8789Y376072D03*
X6944Y414616D03*
X6855Y436844D03*
X6750Y425868D03*
X7180Y449205D03*
X62439Y413744D03*
X66931Y398350D03*
X74863Y390483D03*
X64055Y389700D03*
X33722Y401639D03*
X74544Y414071D03*
X70779Y402387D03*
X79016Y410283D03*
X35738Y406956D03*
X14422Y411528D03*
X14657Y416838D03*
X10615Y411073D03*
X26551Y394546D03*
X30232Y416556D03*
X23922Y415548D03*
X35994Y410146D03*
X43719Y414419D03*
X32141Y407501D03*
X31808Y410684D03*
X18448Y402542D03*
X74817Y409752D03*
X26972Y399588D03*
X70882Y409794D03*
X66938Y410045D03*
X78939Y414083D03*
X18448Y406788D03*
X53976Y389814D03*
X74894Y398251D03*
X62031Y399713D03*
X70775Y398396D03*
X70845Y405839D03*
X70952Y414050D03*
X54515Y396433D03*
X54463Y386651D03*
X70865Y390502D03*
X74702Y394300D03*
X74869Y406315D03*
X78300Y386505D03*
X64948Y386626D03*
X78362Y398337D03*
X77963Y381183D03*
X70888Y394222D03*
X66963Y473083D03*
X66931Y484968D03*
X79081Y465348D03*
X70704Y429620D03*
X67015Y449433D03*
X74639Y441855D03*
X78754Y453353D03*
X78811Y426113D03*
X52151Y456887D03*
X66903Y457689D03*
X78798Y433983D03*
X17072Y435057D03*
X74836Y453477D03*
X59980Y482517D03*
X78754Y449904D03*
X67112Y481066D03*
X70488Y465291D03*
X74450Y457429D03*
X70713Y461504D03*
X36237Y441728D03*
X70908Y457771D03*
X70898Y418271D03*
X61038Y424878D03*
X74726Y425594D03*
X59209Y438908D03*
X46853Y441796D03*
X78561Y421756D03*
X70809Y438057D03*
X43659Y432766D03*
X43088Y438073D03*
X45486Y456341D03*
X38566Y451290D03*
X42312Y463368D03*
X74780Y429794D03*
X24357Y423051D03*
X37988Y438328D03*
X19757Y418538D03*
X29472Y428016D03*
X78738Y429679D03*
X11964Y421332D03*
X52476Y439395D03*
X13062Y429279D03*
X74656Y421838D03*
X17936Y431103D03*
X14206Y433632D03*
X15424Y422722D03*
X70857Y433857D03*
X19015Y426461D03*
X14147Y438989D03*
X74752Y437655D03*
X74437Y473159D03*
X15872Y441916D03*
X74460Y461287D03*
X78793Y445704D03*
X70868Y477094D03*
X23748Y436249D03*
X26611Y441743D03*
X70909Y469595D03*
X30513Y437850D03*
X74702Y469183D03*
X37420Y461517D03*
X31517Y445328D03*
X70868Y473157D03*
X28472Y447107D03*
X48298Y454813D03*
X70602Y453533D03*
X79050Y457367D03*
X74805Y481031D03*
X66991Y476766D03*
X62798Y461555D03*
X74451Y465323D03*
X79094Y441620D03*
X74801Y433368D03*
X70869Y421840D03*
X70759Y449277D03*
X74805Y477094D03*
X70868Y481031D03*
X74598Y485021D03*
X78421Y473078D03*
X74695Y449260D03*
X59063Y485583D03*
X79134Y461339D03*
X78742Y488905D03*
X66961Y488885D03*
X74805Y492842D03*
X74870Y488789D03*
X69523Y567387D03*
X69555Y564187D03*
X69569Y594959D03*
X69520Y560987D03*
X68421Y570392D03*
X69323Y579887D03*
X69518Y604727D03*
X69599Y601527D03*
X69569Y598159D03*
X69388Y576660D03*
X69450Y573460D03*
X69569Y608021D03*
X69496Y611417D03*
X69661Y591387D03*
X66579Y592250D03*
X63125Y592801D03*
X62681Y589462D03*
X69451Y684303D03*
Y681103D03*
X68928Y687846D03*
X69316Y697605D03*
X69451Y691003D03*
X69474Y694403D03*
X69523Y718313D03*
Y715113D03*
X69472Y729385D03*
X69548Y726185D03*
X69558Y711913D03*
X68620Y722610D03*
X106419Y310245D03*
X126184Y310860D03*
X93200Y308800D03*
X145771Y414191D03*
X82555Y406288D03*
X110472Y394496D03*
X145765Y406438D03*
X122053Y406224D03*
X114175Y410161D03*
X125990Y394413D03*
X141738D03*
X98427Y414098D03*
X125990D03*
X90553Y410161D03*
X102263Y414083D03*
X141887Y410202D03*
X102364Y406224D03*
X133864Y410161D03*
X94367Y394479D03*
X102364Y402287D03*
X106301Y398350D03*
Y402287D03*
X102364Y398350D03*
X110238Y402287D03*
X114175D03*
X110238Y398350D03*
X114175D03*
X85721Y385798D03*
X149362Y413951D03*
X149498Y406396D03*
X145795Y410173D03*
X149431Y394402D03*
X149783Y390487D03*
X110238Y410161D03*
X141738Y414098D03*
X133863Y413773D03*
X114175Y414098D03*
X122053D03*
X125990Y410161D03*
X94579Y406324D03*
X118130Y398511D03*
X98427Y410161D03*
X90553Y414098D03*
X86563Y402383D03*
X133964Y394555D03*
X102555Y394412D03*
X86616Y394413D03*
X86463Y390483D03*
X114175Y406224D03*
X126063Y406183D03*
X141738Y406224D03*
X106301D03*
X149663Y410083D03*
X82459Y413976D03*
X90566Y394383D03*
X82663Y402406D03*
X133864Y402287D03*
X86772Y414047D03*
X122053Y402287D03*
X133864Y398350D03*
X137801D03*
X122053D03*
X137801Y402287D03*
X125990D03*
Y398350D03*
X129927Y402287D03*
Y398350D03*
X82663Y398383D03*
X141738Y402287D03*
Y398350D03*
X145865Y402287D03*
Y398350D03*
X149488Y402114D03*
X149583Y398383D03*
X90359Y469275D03*
X137801Y453472D03*
Y445598D03*
X133864Y437720D03*
Y445598D03*
X133953Y425813D03*
X102684Y445671D03*
X106263Y437583D03*
X133864Y433783D03*
X102364Y429846D03*
X98363Y421883D03*
X94263Y418129D03*
X106210Y421976D03*
X110332Y425814D03*
X149612Y445598D03*
Y433783D03*
X86493Y441401D03*
X86616Y433783D03*
X86687Y421669D03*
X137801Y477094D03*
X149612D03*
X114175D03*
X102364D03*
X98626Y477049D03*
X130081Y425912D03*
X121943Y425834D03*
X114091Y425962D03*
X122053Y421972D03*
Y418035D03*
X106301D03*
X114175D03*
X133863Y417883D03*
X117951Y437592D03*
X114175Y445598D03*
X110263Y441683D03*
X118189Y445711D03*
X125990Y445598D03*
X110238Y437720D03*
X125990D03*
X110222Y417989D03*
X106341Y426062D03*
X82564Y449659D03*
X145663Y441483D03*
X98288Y441609D03*
X149612Y429846D03*
X110238Y453472D03*
X122053Y429846D03*
X114063Y429879D03*
X125897Y453240D03*
X118238Y453417D03*
X149594Y480923D03*
X94518Y449186D03*
X86768Y449383D03*
X98427Y484968D03*
Y481031D03*
X102364D03*
Y484968D03*
X106301D03*
Y481031D03*
X114175Y484968D03*
Y481031D03*
X122053Y484968D03*
Y481031D03*
X125990Y484968D03*
Y481031D03*
X145567Y453547D03*
X145763Y449583D03*
X149576Y465497D03*
X98597Y457291D03*
X94490Y429846D03*
X90463Y425983D03*
X90480Y437608D03*
X82562Y425980D03*
X86505Y425987D03*
X90380Y429650D03*
X130080Y457372D03*
X94490Y437720D03*
X82681Y430041D03*
X141827Y461346D03*
X98334Y429754D03*
X98427Y437720D03*
X94369Y425977D03*
X82677Y433595D03*
X149563Y469220D03*
X94490Y433783D03*
X141738Y481031D03*
X82663Y457486D03*
X141738Y484968D03*
X98433Y449125D03*
X137801Y481031D03*
X102600Y425983D03*
X137801Y484968D03*
X94554Y421911D03*
X133864Y481031D03*
X149612Y437720D03*
X94414Y445605D03*
X133864Y484968D03*
X86663Y429536D03*
X82542Y445403D03*
X98427Y433783D03*
X86568Y445669D03*
X90426Y449431D03*
X90563Y417983D03*
X145675Y425909D03*
X82573Y441360D03*
X145675Y437720D03*
X98280Y445405D03*
X90426Y441880D03*
X145675Y481031D03*
Y484968D03*
X145737Y418077D03*
X145675Y473157D03*
Y465283D03*
X149719Y457328D03*
X129927Y473157D03*
Y465283D03*
X137801Y461346D03*
Y457409D03*
X114175Y473157D03*
X122053Y469220D03*
X110263Y469083D03*
X122053Y473157D03*
X90350Y473069D03*
X82679Y477094D03*
X90662Y461604D03*
X106263Y453483D03*
X106449Y465157D03*
X122053Y445598D03*
X126180Y418224D03*
X137801Y437720D03*
X137767Y425993D03*
X129927Y445598D03*
X141738Y449535D03*
X133864Y421972D03*
Y429846D03*
X98533Y418180D03*
X118134Y449362D03*
X106363Y441583D03*
X110238Y445598D03*
X110289Y422113D03*
X122053Y437720D03*
X114175D03*
X94661Y441681D03*
X106263Y433683D03*
X90544Y433408D03*
X90408Y421930D03*
X129927Y437720D03*
X141738Y429846D03*
X86663Y453583D03*
X82732Y453139D03*
X102227Y473344D03*
X145675Y469220D03*
X90376Y476918D03*
X110238Y477094D03*
X141738D03*
X137801Y473157D03*
X98427Y469046D03*
X106301Y469220D03*
X114175D03*
X126057Y469287D03*
X129927Y469220D03*
X137801D03*
X122053Y465283D03*
X133864D03*
X106301Y461346D03*
X122113Y457535D03*
X129963Y461283D03*
X110263Y457283D03*
X122158Y453388D03*
X125990Y477094D03*
X137801Y449535D03*
X149612Y425909D03*
X82535Y461227D03*
X83021Y473118D03*
X141595Y421932D03*
X141775Y426153D03*
X86735Y461382D03*
X141763Y437883D03*
X86937Y477160D03*
X141682Y417902D03*
X82759Y469436D03*
X145663Y445583D03*
X145675Y429846D03*
X142008Y457429D03*
X141863Y445583D03*
X86959Y469276D03*
X137570Y421843D03*
X145561Y421879D03*
X90965Y465270D03*
X129927Y481031D03*
Y484968D03*
X110238Y481031D03*
Y484968D03*
X94490Y481031D03*
X86663Y457283D03*
X94490Y484968D03*
X86765Y465205D03*
X138061Y418151D03*
X145675Y433783D03*
X82763Y417750D03*
X86523Y417943D03*
X94844Y469182D03*
X102469Y469134D03*
X106149Y457371D03*
X141649Y453189D03*
X149620Y485149D03*
X98682Y461441D03*
X94092Y492819D03*
X141738Y488905D03*
X110238D03*
X125990D03*
X94377Y489070D03*
X118004Y488825D03*
X133864Y488905D03*
X149612D03*
X102308Y488978D03*
X86616Y488905D03*
X91852Y563129D03*
X91156Y572112D03*
X90823Y581387D03*
X91343Y598284D03*
X91023Y606587D03*
X90923Y616187D03*
X91198Y595087D03*
X91123Y591887D03*
X91223Y588487D03*
X159768Y238444D03*
X160004Y233894D03*
X181576Y407810D03*
X175463Y413760D03*
X161499Y402554D03*
X169297Y402536D03*
X157502Y390427D03*
X173425Y390228D03*
X214660Y362600D03*
X176751Y387090D03*
X157251Y414149D03*
X161477Y394511D03*
X180991Y398678D03*
X180809Y414170D03*
X179225Y403667D03*
X203410Y394323D03*
X182378Y390377D03*
X157574Y394185D03*
X161241Y398226D03*
X161277Y414114D03*
X174124Y402624D03*
X161213Y390551D03*
X169503Y386977D03*
X153587Y406496D03*
X157554Y402251D03*
X157698Y406313D03*
X161475Y410299D03*
X165266Y409882D03*
X165337Y414489D03*
X153528Y410052D03*
X165455Y398256D03*
X165229Y402019D03*
X157411Y398513D03*
X169113Y398299D03*
X178031Y390023D03*
X177588Y482616D03*
X161423Y469220D03*
X153583Y461058D03*
X169297Y477094D03*
Y465283D03*
X157486Y437720D03*
Y429846D03*
X153416Y445539D03*
X169290Y417960D03*
X169297Y437720D03*
X169112Y453260D03*
X169166Y429679D03*
X153549Y429846D03*
X165621Y418066D03*
X153549Y425909D03*
X161746Y421972D03*
X177182Y467018D03*
X175477Y472360D03*
X176815Y479061D03*
X161473Y457213D03*
X165360Y477094D03*
X153549Y437720D03*
X157560Y445484D03*
X153549Y449535D03*
X174859Y469220D03*
X157322Y453385D03*
X165317Y461561D03*
X165360Y473157D03*
X161455Y453385D03*
X177763Y486293D03*
X153463Y453383D03*
X157411Y469344D03*
X161423Y477094D03*
X157486Y461346D03*
X153690Y469111D03*
X165411Y429590D03*
X175161Y434723D03*
X161423Y445598D03*
X153549Y421972D03*
X161423Y484968D03*
Y481031D03*
X157486Y473157D03*
X165360Y469220D03*
X153549Y477094D03*
X173234Y465283D03*
Y453472D03*
X174086Y484839D03*
X175150Y476294D03*
X174351Y429014D03*
X161423Y437720D03*
X153549Y433783D03*
X161363Y425780D03*
X173234Y437720D03*
X173155Y417978D03*
X153422Y441722D03*
X161423Y449430D03*
X153549Y473157D03*
X161670Y418161D03*
X176662Y418122D03*
X153201Y418097D03*
X157401Y418143D03*
X157463Y421883D03*
X157486Y425909D03*
X173458Y457178D03*
X178053Y474260D03*
X174601Y481467D03*
X165319Y453134D03*
X165353Y480812D03*
X157486Y433783D03*
X165360Y421972D03*
X153646Y457393D03*
X161294Y461561D03*
X165363Y425783D03*
X157393Y457572D03*
X165217Y457361D03*
X165355Y433382D03*
X161423Y473157D03*
X165355Y437582D03*
X165360Y445598D03*
X157411Y449556D03*
X169157Y445598D03*
X157508Y480990D03*
X165288Y449306D03*
X157486Y484968D03*
X153601Y480894D03*
X153586Y485118D03*
X161423Y433783D03*
X181414Y490281D03*
X174475Y488016D03*
X178084Y493198D03*
X157486Y488905D03*
X165360D03*
X169297Y492842D03*
X161423D03*
X159589Y817543D03*
X157422Y825918D03*
X158725Y835536D03*
X159688Y832484D03*
X159431Y838974D03*
X159688Y829234D03*
X159137Y820712D03*
X160735Y857183D03*
X154730Y847010D03*
X159688Y851564D03*
X159560Y842172D03*
X159426Y848357D03*
X651000Y467700D03*
X646163Y482677D03*
X643296Y477617D03*
X643914Y470592D03*
X648652Y470028D03*
X654990Y463513D03*
X658399Y460842D03*
X659485Y455066D03*
X666818Y452921D03*
X710645Y447266D03*
X678767Y447136D03*
X672583Y467901D03*
X667831Y479556D03*
X662166Y456914D03*
X661760Y460089D03*
X646246Y475961D03*
X646794Y472634D03*
X682915Y467823D03*
X708059Y449951D03*
X671145Y454348D03*
X658195Y464248D03*
X653351Y470098D03*
X650837Y472421D03*
X646251Y479161D03*
X675745Y448189D03*
X685815Y496140D03*
X689996Y496274D03*
X694169Y496394D03*
X698475Y496387D03*
X702670Y496148D03*
X707296Y496348D03*
X716700Y445400D03*
X742200Y472500D03*
X724300Y454000D03*
X719100Y478900D03*
X744986Y481255D03*
X749974Y477780D03*
X749628Y471196D03*
X739751Y469686D03*
X735295Y463720D03*
X738636Y457903D03*
X731780Y452531D03*
X729478Y459116D03*
X721600Y451000D03*
X719700Y485600D03*
X735191Y453967D03*
X735231Y457167D03*
X746845Y476389D03*
Y473189D03*
X717993Y451389D03*
X731751Y464398D03*
X735259Y469898D03*
X721445Y455789D03*
X726589Y460909D03*
X743520Y478297D03*
X738745Y472789D03*
X713845Y447289D03*
G54D42*
X43500Y540200D03*
X118263Y415283D03*
X126310Y465403D03*
X102643Y465497D03*
X680800Y534800D03*
X701500D03*
G54D60*
X691905Y448220D03*
X693874D03*
X695842D03*
X697811D03*
Y483820D03*
X695842D03*
X693874D03*
X691905D03*
G54D51*
X102363Y454883D03*
X125579Y427173D03*
X701500Y524200D03*
X680800D03*
G54D24*
X43848Y186291D03*
X30773Y271007D03*
X35107Y271062D03*
X67367Y523339D03*
X63918Y541813D03*
X113749Y310169D03*
X93263Y386883D03*
X107363Y446783D03*
X94500Y462200D03*
X91167Y488194D03*
X181278Y244257D03*
X424282Y433718D03*
X707109Y435023D03*
X698367Y435002D03*
X702508Y435004D03*
X705600Y543600D03*
X663300Y518600D03*
X648200Y544600D03*
X705928Y521245D03*
X668705Y545144D03*
X685815Y489878D03*
X689996Y489847D03*
X698475Y489874D03*
X694196Y489947D03*
X707296D03*
X702648Y489837D03*
X668743Y537665D03*
X726045Y539753D03*
G54D33*
X62358Y211203D03*
X57483Y385340D03*
X55073Y443238D03*
X48131Y476567D03*
X59963Y488683D03*
X51120Y530394D03*
X113763Y306003D03*
X89463Y397283D03*
X171155Y265687D03*
X171111Y261545D03*
X173700Y273900D03*
X173715Y244229D03*
X176608Y289824D03*
X233100Y482400D03*
Y486500D03*
Y478300D03*
Y474200D03*
X427649Y469469D03*
X686400Y545500D03*
X653367Y563931D03*
X693829Y766898D03*
X693807Y762804D03*
X693820Y838158D03*
X693779Y834000D03*
X693800Y829925D03*
X694630Y800492D03*
X694504Y796145D03*
X694293Y791967D03*
X693998Y787599D03*
X693955Y783400D03*
X693934Y779285D03*
X693913Y775149D03*
X693870Y771013D03*
X693947Y854741D03*
X693916Y850609D03*
X693887Y846395D03*
X693868Y842302D03*
X686310Y854661D03*
X726900Y535700D03*
X749500Y554700D03*
Y550600D03*
Y563300D03*
Y559200D03*
X738263Y855068D03*
G54D15*
X6614Y553544D03*
X10551Y623622D03*
X6614Y671654D03*
X10551Y741732D03*
X18425Y553544D03*
X32204D03*
X18425Y623622D03*
X32204D03*
X18425Y671654D03*
X32204D03*
X18425Y741732D03*
X32204D03*
G54D70*
G01X6614Y549842D02*
Y553544D01*
G01D02*
Y557246D01*
G01Y553544D02*
X10316D01*
G01X6849Y623622D02*
X10551D01*
G01X6614Y667952D02*
Y671654D01*
G01D02*
Y675356D01*
G01Y671654D02*
X10316D01*
G01X6849Y741732D02*
X10551D01*
G01X76772Y7633D02*
Y19685D01*
G01X64720D02*
X76772D01*
G01D02*
X88824D01*
G01X29528Y7633D02*
Y19685D01*
G01D02*
Y31737D01*
G01X17476Y19685D02*
X29528D01*
G01D02*
X41580D01*
G01X32204Y549842D02*
Y553544D01*
G01D02*
Y557246D01*
G01X28502Y553544D02*
X32204D01*
G01D02*
X35906D01*
G01X18425Y549842D02*
Y553544D01*
G01D02*
Y557246D01*
G01X14723Y553544D02*
X18425D01*
G01D02*
X22127D01*
G01X32204Y619920D02*
Y623622D01*
G01D02*
Y627324D01*
G01X28502Y623622D02*
X32204D01*
G01D02*
X35906D01*
G01X18425Y619920D02*
Y623622D01*
G01D02*
Y627324D01*
G01X14723Y623622D02*
X18425D01*
G01D02*
X22127D01*
G01X10551Y619920D02*
Y623622D01*
G01D02*
Y627324D01*
G01Y623622D02*
X14253D01*
G01X32204Y667952D02*
Y671654D01*
G01D02*
Y675356D01*
G01X28502Y671654D02*
X32204D01*
G01X18425Y667952D02*
Y671654D01*
G01D02*
Y675356D01*
G01X14723Y671654D02*
X18425D01*
G01D02*
X22127D01*
G01X32204Y738030D02*
Y741732D01*
G01D02*
Y745434D01*
G01X28502Y741732D02*
X32204D01*
G01D02*
X35906D01*
G01X18425Y738030D02*
Y741732D01*
G01D02*
Y745434D01*
G01X14723Y741732D02*
X18425D01*
G01D02*
X22127D01*
G01X10551Y738030D02*
Y741732D01*
G01D02*
Y745434D01*
G01Y741732D02*
X14253D01*
G01X109410Y787529D02*
Y796831D01*
G01D02*
Y806133D01*
G01X100108Y796831D02*
X109410D01*
G01D02*
X118712D01*
G01X143460Y905512D02*
X155512D01*
G01X108268Y893460D02*
Y905512D01*
G01D02*
Y917564D01*
G01X96216Y905512D02*
X108268D01*
G01D02*
X120320D01*
G01X109410Y867095D02*
Y876397D01*
G01D02*
Y885699D01*
G01X100108Y876397D02*
X109410D01*
G01D02*
X118712D01*
G01X182681Y556680D02*
Y560832D01*
G01D02*
Y564984D01*
G01X178529Y560832D02*
X182681D01*
G01D02*
X186833D01*
G01X182681Y576680D02*
Y580832D01*
G01D02*
Y584984D01*
G01X178529Y580832D02*
X182681D01*
G01D02*
X186833D01*
G01X168465Y876397D02*
Y885699D01*
G01X159163Y876397D02*
X168465D01*
G01D02*
X177767D01*
G01X155512Y893460D02*
Y905512D01*
G01D02*
Y917564D01*
G01Y905512D02*
X167564D01*
G01X286982Y823883D02*
Y828335D01*
G01D02*
Y832787D01*
G01X282530Y828335D02*
X286982D01*
G01D02*
X291434D01*
G01X296982Y823883D02*
Y828335D01*
G01D02*
Y832787D01*
G01X292530Y828335D02*
X296982D01*
G01D02*
X301434D01*
G01X306982Y823883D02*
Y828335D01*
G01D02*
Y832787D01*
G01X302530Y828335D02*
X306982D01*
G01D02*
X311434D01*
G01X316982Y823883D02*
Y828335D01*
G01D02*
Y832787D01*
G01X312530Y828335D02*
X316982D01*
G01D02*
X321434D01*
G01X326982Y823883D02*
Y828335D01*
G01D02*
Y832787D01*
G01X322530Y828335D02*
X326982D01*
G01D02*
X331434D01*
G01X336982Y823883D02*
Y828335D01*
G01D02*
Y832787D01*
G01X332530Y828335D02*
X336982D01*
G01D02*
X341434D01*
G01X346982Y823883D02*
Y828335D01*
G01D02*
Y832787D01*
G01X342530Y828335D02*
X346982D01*
G01D02*
X351434D01*
G01X356982Y823883D02*
Y828335D01*
G01D02*
Y832787D01*
G01X352530Y828335D02*
X356982D01*
G01D02*
X361434D01*
G01X366982Y823883D02*
Y828335D01*
G01D02*
Y832787D01*
G01X362530Y828335D02*
X366982D01*
G01D02*
X371434D01*
G01X764200Y813000D02*
X768200D01*
X770184Y814984D01*
X781514D01*
G54D25*
X76300Y144900D03*
X62368Y198735D03*
X72706Y185541D03*
X62359Y202789D03*
X60200Y251200D03*
X62347Y206909D03*
X57483Y381140D03*
X70763Y386683D03*
X55507Y450659D03*
X55550Y455007D03*
X43473Y528179D03*
X83100Y225900D03*
X84550Y409763D03*
X89463Y401383D03*
X88564Y405439D03*
X176564Y294017D03*
X416638Y471346D03*
X416632Y475470D03*
X712245Y485000D03*
Y480900D03*
X693400Y511400D03*
X710826Y560695D03*
X693856Y825792D03*
X712900Y529600D03*
Y525500D03*
X737982Y850566D03*
X737962Y846447D03*
X738100Y859500D03*
G54D52*
X109410Y796831D03*
Y876397D03*
X168465Y796831D03*
Y876397D03*
G54D61*
X701858Y450272D03*
Y452240D03*
Y454209D03*
Y456177D03*
Y458146D03*
Y460114D03*
Y462083D03*
Y464051D03*
Y466020D03*
Y467989D03*
Y469957D03*
Y471926D03*
Y473894D03*
Y475863D03*
Y477831D03*
Y479800D03*
Y481768D03*
X687858D03*
Y479800D03*
Y477831D03*
Y475863D03*
Y473894D03*
Y471926D03*
Y469957D03*
Y467989D03*
Y466020D03*
Y464051D03*
Y462083D03*
Y460114D03*
Y458146D03*
Y456177D03*
Y454209D03*
Y452240D03*
Y450272D03*
G54D34*
X65758Y211203D03*
X60883Y385340D03*
X58473Y443238D03*
X51531Y476567D03*
X63363Y488683D03*
X54520Y530394D03*
X117163Y306003D03*
X92863Y397283D03*
X174555Y265687D03*
X174511Y261545D03*
X177100Y273900D03*
X177115Y244229D03*
X180008Y289824D03*
X236500Y482400D03*
Y486500D03*
Y478300D03*
Y474200D03*
X431049Y469469D03*
X689800Y545500D03*
X656767Y563931D03*
X697229Y766898D03*
X697207Y762804D03*
X697220Y838158D03*
X697179Y834000D03*
X697200Y829925D03*
X698030Y800492D03*
X697904Y796145D03*
X697693Y791967D03*
X697398Y787599D03*
X697355Y783400D03*
X697334Y779285D03*
X697313Y775149D03*
X697270Y771013D03*
X697347Y854741D03*
X697316Y850609D03*
X697287Y846395D03*
X697268Y842302D03*
X689710Y854661D03*
X730300Y535700D03*
X752900Y554700D03*
Y550600D03*
Y563300D03*
Y559200D03*
X741663Y855068D03*
G54D16*
X22980Y59055D03*
X30854D03*
X22980Y106299D03*
Y98425D03*
Y90551D03*
Y82677D03*
Y74803D03*
Y66929D03*
X30854Y106299D03*
Y98425D03*
Y90551D03*
Y82677D03*
Y74803D03*
Y66929D03*
X41142Y135669D03*
Y155669D03*
Y145669D03*
X26181Y537559D03*
Y527559D03*
Y517559D03*
X41142Y655669D03*
Y645669D03*
Y635669D03*
Y763780D03*
Y753780D03*
Y773780D03*
G54D43*
X43500Y534600D03*
X118263Y409683D03*
X126310Y459803D03*
X102643Y459897D03*
X680800Y529200D03*
X701500D03*
G54D71*
G01X60933Y392640D02*
X63406Y395113D01*
X63938D01*
X66631Y397806D01*
Y398050D01*
X66931Y398350D01*
G01X60933Y389240D02*
Y392640D01*
G01X70713Y386683D02*
Y390350D01*
X70865Y390502D01*
G01X57433Y392640D02*
Y393640D01*
X61106Y397313D01*
X63026D01*
X64431Y398718D01*
Y400566D01*
X69704Y405839D01*
X70845D01*
G01X57433Y385340D02*
X55774D01*
X54463Y386651D01*
G01X57433Y389240D02*
Y385340D01*
G01X66931Y484968D02*
X63413Y488486D01*
G01X51581Y476567D02*
X51422Y476408D01*
Y473540D01*
G01X55457Y450659D02*
X55500Y450702D01*
Y455007D01*
G01D02*
X54031D01*
X52151Y456887D01*
G01X90813Y225400D02*
Y228783D01*
G01X121313Y305503D02*
Y306333D01*
X122715Y307735D01*
Y311826D01*
X124577Y313688D01*
Y317851D01*
X124275Y318153D01*
G01D02*
X127795D01*
X132512Y313436D01*
Y306987D01*
X132412Y306887D01*
Y306002D01*
X132013Y305603D01*
G01X124275Y318153D02*
X124090Y318338D01*
X113308D01*
X109534Y314564D01*
G01X126184Y310860D02*
Y306874D01*
X124813Y305503D01*
G01X93200Y308800D02*
X94369Y307631D01*
Y305456D01*
G01X89413Y401383D02*
Y404540D01*
X88514Y405439D01*
G01D02*
X83404D01*
X82555Y406288D01*
G01X118263Y409483D02*
X118163Y409383D01*
X114953D01*
X114175Y410161D01*
G01X130163Y413433D02*
X129963Y413233D01*
X126855D01*
X125990Y414098D01*
G01X106855Y413570D02*
Y414622D01*
X110222Y417989D01*
G01X88000Y409763D02*
Y411545D01*
X90553Y414098D01*
G01X98138Y402228D02*
X97433D01*
X94579Y405082D01*
Y406324D01*
G01X89413Y397283D02*
Y397210D01*
X86616Y394413D01*
G01X130163Y409933D02*
X129963Y409733D01*
X126418D01*
X125990Y410161D01*
G01X118263Y415483D02*
X115560D01*
X114175Y414098D01*
G01X118413Y421283D02*
X118522Y421174D01*
X118613Y418783D01*
Y415833D01*
X118263Y415483D01*
G01X89163Y386833D02*
X88367D01*
X86463Y388737D01*
Y390483D01*
G01X134663Y456633D02*
Y456610D01*
X137801Y453472D01*
G01X136213Y441583D02*
Y440069D01*
X133864Y437720D01*
G01X132113Y441583D02*
Y443003D01*
X133864Y444754D01*
Y445598D01*
G01X137163Y434433D02*
X134514D01*
X133864Y433783D01*
G01X114913Y421283D02*
X114905D01*
X112463Y423626D01*
Y423683D01*
X110332Y425814D01*
G01X102363Y449083D02*
Y445992D01*
X102684Y445671D01*
G01D02*
X102967D01*
X102999Y445703D01*
X106333D01*
X107363Y446733D01*
G01X119313Y433683D02*
Y436230D01*
X117951Y437592D01*
G01X115013Y448583D02*
Y446436D01*
X114175Y445598D01*
G01X113413Y441583D02*
X110363D01*
X110263Y441683D01*
G01X121013Y441583D02*
Y442887D01*
X118189Y445711D01*
G01D02*
X121813Y449335D01*
Y449983D01*
G01X126310Y459603D02*
X127680Y458233D01*
Y456377D01*
X129713Y454344D01*
Y452683D01*
G01D02*
Y449183D01*
G01D02*
X129575D01*
X125990Y445598D01*
G01X109513Y434383D02*
Y436995D01*
X110238Y437720D01*
G01X110813Y430483D02*
Y431233D01*
X109513Y432533D01*
Y434383D01*
G01X102363Y455083D02*
X100805D01*
X98597Y457291D01*
G01X102643Y459697D02*
X101003D01*
X98597Y457291D01*
G01X133213Y452683D02*
Y449183D01*
G01X126310Y465603D02*
X129607D01*
X129927Y465283D01*
G01X118163Y474433D02*
X115451D01*
X114175Y473157D01*
G01X146349Y461877D02*
Y464609D01*
X145675Y465283D01*
G01X139713Y441583D02*
Y439632D01*
X137801Y437720D01*
G01X128613Y441583D02*
Y439034D01*
X129927Y437720D01*
G01X137163Y430933D02*
X134951D01*
X133864Y429846D01*
G01X111513Y448583D02*
Y446873D01*
X110238Y445598D01*
G01X116913Y441583D02*
Y440458D01*
X114175Y437720D01*
G01X125313Y449983D02*
Y448858D01*
X122053Y445598D01*
G01X124513Y441583D02*
Y440180D01*
X122053Y437720D01*
G01X107313Y430483D02*
X106263Y431533D01*
Y433683D01*
G01X134663Y460133D02*
X136588D01*
X137801Y461346D01*
G01X114175Y437720D02*
X113013Y436558D01*
Y434383D01*
G01X122053Y437720D02*
X122813Y436960D01*
Y433683D01*
G01X133213Y449183D02*
Y448353D01*
X131443Y446583D01*
X130912D01*
X129927Y445598D01*
G01X91167Y491644D02*
X91751D01*
X94325Y489070D01*
X94377D01*
G01X171746Y269694D02*
X169795D01*
X168010Y267909D01*
G01X181278Y244207D02*
X184050D01*
X185299Y245456D01*
X185563D01*
G01X180058Y289824D02*
X180143Y289861D01*
X183707D01*
G01X149849Y461877D02*
X152764D01*
X153583Y461058D01*
G01X157113Y440683D02*
Y438093D01*
X157486Y437720D01*
G01X160613Y440683D02*
Y438530D01*
X161423Y437720D01*
G01X711500Y438300D02*
Y437500D01*
X708973Y434973D01*
X707109D01*
G01X675915Y463877D02*
Y467377D01*
G01X667831Y479556D02*
X668964Y478423D01*
X672209D01*
G01X675915Y467377D02*
X673107D01*
X672583Y467901D01*
G01X707890Y467821D02*
X707880Y467811D01*
X707980Y464221D01*
G01X768000Y457700D02*
X770950Y460650D01*
X781514D01*
G54D26*
X65768Y198735D03*
X76106Y185541D03*
X65759Y202789D03*
X63600Y251200D03*
X65747Y206909D03*
X60883Y381140D03*
X74163Y386683D03*
X58907Y450659D03*
X58950Y455007D03*
X46873Y528179D03*
X79700Y144900D03*
X86500Y225900D03*
X87950Y409763D03*
X92863Y401383D03*
X91964Y405439D03*
X179964Y294017D03*
X420038Y471346D03*
X420032Y475470D03*
X696800Y511400D03*
X697256Y825792D03*
X715645Y485000D03*
Y480900D03*
X716300Y529600D03*
Y525500D03*
X714226Y560695D03*
X741382Y850566D03*
X741362Y846447D03*
X741500Y859500D03*
G54D53*
X172508Y238287D03*
X180108D03*
X680225Y486151D03*
X672625D03*
X679809Y478423D03*
X672209D03*
G54D17*
X29528Y19685D03*
X76772D03*
X108268Y905512D03*
X155512D03*
G54D44*
X62977Y500748D03*
G54D35*
X25600Y274900D03*
X18900Y306200D03*
X76251Y401844D03*
X56569Y399551D03*
X58691Y404840D03*
X66136Y371769D03*
X79502Y394485D03*
X71915Y366033D03*
X73615Y371533D03*
X48515Y482733D03*
X65382Y422433D03*
X33315Y473433D03*
X77915Y469095D03*
X64415Y446133D03*
X70613Y484810D03*
X63000Y471442D03*
X41215Y474533D03*
X33715Y481333D03*
X41262Y467436D03*
X32548Y465241D03*
X56795Y466429D03*
X57663Y473783D03*
X46007Y446236D03*
X34821Y456887D03*
X50845Y466404D03*
X53815Y485033D03*
X41015Y485433D03*
X73550Y503589D03*
X76740Y498969D03*
X69815Y499033D03*
X69615Y493333D03*
X79160Y504249D03*
X58715Y590333D03*
X74724Y588857D03*
X57515Y708733D03*
X73715Y711333D03*
X97821Y397330D03*
X81535Y388844D03*
X110315Y406333D03*
X81415Y371233D03*
X80700Y377000D03*
X81946Y383090D03*
X98215Y425833D03*
X102388Y440622D03*
X117915Y427033D03*
X102508Y434585D03*
X106050Y477138D03*
X150029Y473321D03*
X85871Y485571D03*
X117815Y480433D03*
X95200Y474700D03*
X80416Y481610D03*
X134215Y475533D03*
X134163Y469043D03*
X141715Y467833D03*
X149563Y441783D03*
X141811Y433800D03*
X145782Y477006D03*
X146090Y457318D03*
X110050Y461812D03*
X81029Y495229D03*
X88215Y497733D03*
X84549Y502012D03*
X86015Y608633D03*
X84951Y579808D03*
X84752Y588361D03*
X95136Y592963D03*
X80915Y601033D03*
X87148Y596126D03*
X97296Y715873D03*
X83715Y700033D03*
X97047Y707261D03*
X107786Y704092D03*
X99706Y699717D03*
X86515Y707633D03*
X168824Y458743D03*
X153915Y465533D03*
X159663Y465693D03*
X173765Y461522D03*
X168118Y483682D03*
X187021Y462557D03*
X179407Y452283D03*
X182377Y474560D03*
X188616Y476694D03*
X194083Y469148D03*
X187689Y456913D03*
X183070Y466936D03*
X187600Y444200D03*
X184252Y439562D03*
X186200Y449700D03*
X172615Y442533D03*
X157500Y476921D03*
X193581Y457779D03*
X172415Y478733D03*
X165317Y465426D03*
X188457Y468481D03*
X166615Y442233D03*
X178300Y440135D03*
X169917Y489083D03*
X170474Y500652D03*
X164711Y495322D03*
X172992Y494239D03*
X709315Y443333D03*
G54D62*
X694858Y466020D03*
G54D72*
G01X42700Y110500D02*
X42350Y110850D01*
X38350D01*
X25050Y124150D01*
Y167950D01*
X7200Y185800D01*
Y325226D01*
X9243Y327269D01*
Y334400D01*
G01X51800Y93500D02*
Y94374D01*
X22968Y123206D01*
Y167769D01*
X5200Y185537D01*
Y422064D01*
X4800Y422464D01*
Y449876D01*
X8788Y453864D01*
G01X21300Y468000D02*
X16500Y463200D01*
X14300D01*
X3200Y452100D01*
Y419200D01*
X3600Y418800D01*
Y184874D01*
X21368Y167106D01*
Y122543D01*
X47955Y95956D01*
Y93845D01*
X51900Y89900D01*
G01X63100Y107300D02*
X55500Y114900D01*
Y155200D01*
X45068Y165632D01*
X29632D01*
X8800Y186464D01*
Y324563D01*
X11043Y326806D01*
Y336957D01*
X6801Y341199D01*
Y412068D01*
X8644Y413911D01*
Y433623D01*
X9139Y434118D01*
Y449147D01*
X24315Y464323D01*
Y472668D01*
G01X76107Y131131D02*
X73200Y134038D01*
Y141850D01*
X76250Y144900D01*
G01X74800Y87750D02*
X68000D01*
G01X67300Y107200D02*
Y108200D01*
X59700Y115800D01*
Y154585D01*
X59715Y154600D01*
X47001Y167314D01*
X30213D01*
X10400Y187127D01*
Y323900D01*
X14200Y327700D01*
Y339400D01*
G01X77200Y95500D02*
Y99500D01*
X76800Y99900D01*
G01X74800Y91250D02*
Y93100D01*
X77200Y95500D01*
G01X76250Y144900D02*
Y148850D01*
G01X43851Y178778D02*
X29022D01*
X22000Y185800D01*
Y208600D01*
X40500Y227100D01*
G01X29600Y200100D02*
Y207400D01*
X35098Y212898D01*
X47740D01*
G01X61955Y188964D02*
X54036D01*
X51026Y191974D01*
X50244D01*
G01X26100Y187300D02*
X28000D01*
X30200Y189500D01*
X43607D01*
X43848Y189741D01*
G01D02*
X46081Y191974D01*
X50244D01*
G01X56759Y199321D02*
Y199859D01*
X59689Y202789D01*
X62309D01*
G01D02*
Y198744D01*
X62318Y198735D01*
G01D02*
Y196200D01*
X63700Y194818D01*
G01X72656Y185541D02*
Y182756D01*
X71100Y181200D01*
G01X43851Y182278D02*
X43878D01*
X46600Y185000D01*
X62294D01*
X65830Y181464D01*
G01D02*
X66094Y181200D01*
X71100D01*
G01X43794Y193708D02*
X43008D01*
X41400Y192100D01*
X28800D01*
X27800Y191100D01*
G01X65818Y198735D02*
Y198482D01*
X69100Y195200D01*
G01X74700Y191700D02*
X71200Y195200D01*
X69100D01*
G01X50500Y243100D02*
Y264200D01*
X47100Y267600D01*
G01D02*
X40188Y274512D01*
X35107D01*
G01D02*
Y275993D01*
X33500Y277600D01*
X31200D01*
X30424Y278376D01*
Y283267D01*
G01X87263Y264658D02*
X88515Y263406D01*
Y259990D01*
X86653Y258128D01*
X77963D01*
G01X90652Y265960D02*
Y259129D01*
X87091Y255568D01*
X77963D01*
G01X94051Y265872D02*
X92252Y264073D01*
Y258466D01*
X86794Y253008D01*
X77963D01*
G01X30773Y274457D02*
X26043D01*
X25600Y274900D01*
G01X118219Y274497D02*
Y270730D01*
X110158Y262669D01*
Y261096D01*
X105225Y256163D01*
X92212D01*
X86497Y250448D01*
X77963D01*
G01X63650Y251200D02*
X66700D01*
X67800Y250100D01*
G01D02*
X70012Y247888D01*
X77963D01*
G01X121599Y274869D02*
X121327Y274597D01*
Y271575D01*
X111758Y262006D01*
Y260433D01*
X105888Y254563D01*
X92875D01*
X86200Y247888D01*
X77963D01*
G01X113558Y261260D02*
Y259970D01*
X104797Y251209D01*
X100136D01*
X93785Y244858D01*
X78438D01*
X77963Y245333D01*
G01X103610Y268626D02*
X103425D01*
X99042Y273009D01*
X86290D01*
X85816Y273483D01*
X77963D01*
G01X67039Y272085D02*
X68943D01*
X70105Y270923D01*
X77963D01*
G01X107887Y266647D02*
X103042D01*
X98766Y270923D01*
X77963D01*
G01X101242Y265901D02*
Y266184D01*
X98240Y269186D01*
X87483D01*
X81540Y263243D01*
X77963D01*
G01D02*
X73425D01*
X70515Y260333D01*
X70415D01*
G01X77963Y242773D02*
X74103D01*
X70188Y238858D01*
Y224633D01*
G01X62308Y211203D02*
Y216753D01*
X70188Y224633D01*
G01X62297Y206909D02*
Y209792D01*
X62308Y211203D01*
G01X74869Y406315D02*
Y404469D01*
X72475Y402075D01*
Y397691D01*
X70706Y395922D01*
X70183D01*
X68163Y393902D01*
Y385598D01*
X65727Y383162D01*
Y378194D01*
X69006Y374915D01*
Y364600D01*
X47744Y343338D01*
Y277856D01*
X52300Y273300D01*
Y238900D01*
X40500Y227100D01*
G01X47740Y212898D02*
X52884Y207754D01*
Y206821D01*
G01X31100Y313550D02*
X29699Y314951D01*
Y352699D01*
X29700Y352700D01*
Y355000D01*
G01X27000Y313550D02*
X27799Y314349D01*
Y357985D01*
X27284Y358500D01*
G01X18900Y306200D02*
Y301667D01*
X21000Y299567D01*
X25304D01*
G01X22900Y310150D02*
X21650D01*
X18900Y307400D01*
Y306200D01*
G01X70908Y457771D02*
X69349D01*
X67265Y459855D01*
X61613D01*
X60579Y460889D01*
X54031D01*
X52329Y459187D01*
X28085D01*
X24562Y455664D01*
X20182D01*
X12339Y447821D01*
Y430961D01*
X10264Y428886D01*
Y413127D01*
X8915Y411778D01*
Y380614D01*
X10489Y379040D01*
Y375367D01*
X9042Y373920D01*
Y344558D01*
X14200Y339400D01*
G01X32984Y283267D02*
X38566D01*
X39236Y283937D01*
G01D02*
X43111D01*
X43415Y283633D01*
X45215D01*
G01X95146Y279609D02*
X94353Y280402D01*
X89962D01*
X86646Y283718D01*
X77963D01*
G01X27864Y299567D02*
Y303836D01*
X25700Y306000D01*
Y306400D01*
G01X27000Y310050D02*
X25700Y308750D01*
Y306400D01*
G01X25600Y274900D02*
Y277959D01*
X27864Y280223D01*
Y283267D01*
G01X98546Y279609D02*
X96153Y282002D01*
X90626D01*
X86350Y286278D01*
X77963D01*
G01D02*
X71270D01*
X70315Y287233D01*
X70118D01*
G01X30424Y299567D02*
Y306024D01*
X30700Y306300D01*
G01X31100Y310050D02*
X30700Y309650D01*
Y306300D01*
G01X104413Y278608D02*
X103464D01*
X98469Y283603D01*
X91288D01*
X86058Y288833D01*
X77963D01*
G01D02*
X74384D01*
X70015Y293202D01*
Y294733D01*
G01X114229Y270684D02*
X103630D01*
X99705Y274609D01*
X86953D01*
X85524Y276038D01*
X77963D01*
G01X112042Y275903D02*
X110779D01*
X107555Y272679D01*
X103898D01*
X100368Y276209D01*
X87616D01*
X85227Y278598D01*
X77963D01*
G01X117027Y278475D02*
X115599D01*
X114818Y279256D01*
X111600D01*
X107278Y274934D01*
X103906D01*
X101031Y277809D01*
X90292D01*
X86943Y281158D01*
X77963D01*
G01D02*
X71663D01*
X70238Y279733D01*
G01X107750Y277953D02*
X100500Y285203D01*
X91951D01*
X85761Y291393D01*
X77963D01*
G01X33722Y401639D02*
Y394233D01*
G01X74544Y414071D02*
X73774D01*
X71997Y412294D01*
X66782D01*
X61628Y407140D01*
X56608D01*
X55443Y405975D01*
X53993D01*
X48368Y400350D01*
Y394426D01*
X41545Y387603D01*
Y384363D01*
X40411Y383229D01*
X39847D01*
X37664Y385411D01*
X37100D01*
X36532Y384843D01*
Y384279D01*
X38715Y382097D01*
Y381533D01*
X38147Y380965D01*
X37583D01*
X35400Y383147D01*
X34836D01*
X34268Y382579D01*
Y382015D01*
X36451Y379833D01*
Y379269D01*
X35883Y378701D01*
X35319D01*
X33136Y380883D01*
X32572D01*
X32004Y380315D01*
Y379751D01*
X34187Y377569D01*
Y377005D01*
X33619Y376437D01*
X33055D01*
X30872Y378619D01*
X30308D01*
X29740Y378051D01*
Y377487D01*
X31923Y375305D01*
Y374741D01*
X31355Y374173D01*
X30791D01*
X27052Y377911D01*
X26416D01*
X25920Y377415D01*
Y376779D01*
X29659Y373041D01*
Y372477D01*
X29091Y371909D01*
X28527D01*
X24282Y376152D01*
X23646D01*
X23150Y375656D01*
Y375020D01*
X27395Y370777D01*
Y370213D01*
X25836Y368654D01*
X25200D01*
X18984Y374870D01*
Y375505D01*
X33722Y390243D01*
Y394233D01*
G01X70898Y418271D02*
X68863D01*
X66836Y416244D01*
X61402D01*
X55730Y410572D01*
X51798D01*
X48182Y406956D01*
X35738D01*
G01X94490Y429846D02*
X92986Y431350D01*
X89675D01*
X89561Y431236D01*
X85958D01*
X84381Y429659D01*
Y429336D01*
X83386Y428341D01*
X82518D01*
X80672Y426495D01*
Y425569D01*
X79359Y424256D01*
X75793D01*
X75431Y423894D01*
X74021D01*
X72775Y425140D01*
X64836D01*
X63082Y423386D01*
Y423385D01*
X55837Y416140D01*
X40134D01*
X37222Y413228D01*
X18115D01*
G01X10615Y411073D02*
X12770Y413228D01*
X18115D01*
G01X26551Y394546D02*
X24702Y392697D01*
Y386544D01*
X20458Y382300D01*
X18866D01*
X12089Y375523D01*
Y374704D01*
X10642Y373257D01*
Y348994D01*
X11092Y348544D01*
X20915D01*
G01X90463Y425983D02*
X87849Y423369D01*
X85977D01*
X78391Y415783D01*
X78234D01*
X77239Y414788D01*
Y413229D01*
X75581Y411571D01*
X74231D01*
X73117Y410457D01*
Y409624D01*
X71032Y407539D01*
X69282D01*
X63156Y401413D01*
X61326D01*
X60331Y400418D01*
Y399224D01*
X54718Y393611D01*
Y393009D01*
X41769Y380060D01*
Y378410D01*
X29145Y365786D01*
Y364607D01*
X28048Y363510D01*
X25627D01*
X23283Y361166D01*
Y352904D01*
X24487Y351700D01*
Y349135D01*
X23896Y348544D01*
X20915D01*
G01X74726Y425594D02*
X74380Y425940D01*
X64504D01*
X62281Y423717D01*
Y423716D01*
X56305Y417740D01*
X37356D01*
X36906Y417290D01*
Y415278D01*
X36456Y414828D01*
X30682D01*
X30232Y415278D01*
Y416556D01*
G01X78561Y421756D02*
X76143Y419338D01*
X72936D01*
X72420Y419853D01*
X72302Y419971D01*
X69063D01*
X66136Y417044D01*
X61070D01*
X56198Y412172D01*
X50950D01*
X47334Y408556D01*
X37584D01*
X35994Y410146D01*
G01D02*
X37566D01*
X39115Y411695D01*
X39244D01*
G01X43719Y414419D02*
X46200Y411938D01*
X46741D01*
G01X82562Y425980D02*
X82552D01*
X80028Y423456D01*
X77856D01*
X76356Y421956D01*
Y421133D01*
X75361Y420138D01*
X73951D01*
X72956Y421133D01*
Y422158D01*
X71574Y423540D01*
X70164D01*
X64468Y417844D01*
X60738D01*
X57434Y414540D01*
X43840D01*
X43719Y414419D01*
G01X31808Y410684D02*
X28866D01*
X28315Y410133D01*
X27715D01*
G01X18448Y402542D02*
X16949Y404041D01*
X12456D01*
X10865Y402450D01*
Y385671D01*
X12125Y384411D01*
X19950D01*
X22646Y387107D01*
Y397233D01*
G01X86505Y425987D02*
X86331D01*
X77727Y417383D01*
X77570D01*
X75958Y415771D01*
X70268D01*
X68391Y413894D01*
X66119D01*
X60965Y408740D01*
X57075D01*
X55706Y407371D01*
X53125D01*
X49355Y403601D01*
X24129D01*
X22646Y402118D01*
Y397233D01*
G01X74817Y409752D02*
Y409630D01*
X72545Y407358D01*
Y405134D01*
X71498Y404087D01*
X70074D01*
X69075Y403088D01*
Y398089D01*
X66648Y395662D01*
Y385921D01*
X64185Y383458D01*
Y373720D01*
X66136Y371769D01*
G01X90380Y429650D02*
X88205Y427475D01*
Y425282D01*
X87092Y424169D01*
X85645D01*
X78059Y416583D01*
X77902D01*
X76439Y415120D01*
Y413561D01*
X75249Y412371D01*
X73899D01*
X73022Y411494D01*
X70177D01*
X68672Y409989D01*
Y409374D01*
X62529Y403231D01*
X60335D01*
X59644Y402540D01*
X53564D01*
X51798Y400774D01*
Y392352D01*
X21287Y361841D01*
X16415D01*
G01X26972Y399588D02*
X26848Y399464D01*
Y396646D01*
X27248Y396246D01*
X27256D01*
X28251Y395251D01*
Y393841D01*
X26302Y391892D01*
Y385086D01*
X12242Y371026D01*
Y362291D01*
X12692Y361841D01*
X16415D01*
G01X70882Y409794D02*
X70805Y409717D01*
X70328D01*
X62826Y402215D01*
X60451D01*
X57787Y399551D01*
X56569D01*
G01X66938Y410045D02*
X62030Y405137D01*
X58988D01*
X58691Y404840D01*
G01X78939Y414083D02*
X78039Y413183D01*
Y412897D01*
X77316Y412174D01*
Y402909D01*
X76251Y401844D01*
G01X18448Y406788D02*
X19980Y405256D01*
X48746D01*
X52462Y408972D01*
X55262D01*
X61734Y415444D01*
X68299D01*
X69426Y416571D01*
X74925D01*
X77338Y418984D01*
X78194D01*
X84262Y425052D01*
Y427135D01*
X86663Y429536D01*
G01X74702Y394300D02*
X73163Y392761D01*
Y387733D01*
X74213Y386683D01*
G01D02*
Y384331D01*
X73100Y383218D01*
Y380933D01*
G01X78300Y386505D02*
X76263Y384468D01*
Y376385D01*
X81415Y371233D01*
G01X59215Y375233D02*
X60933Y376951D01*
Y381140D01*
G01D02*
Y385340D01*
G01D02*
X63662D01*
X64948Y386626D01*
G01X78362Y398337D02*
X76563Y396538D01*
Y385900D01*
X75463Y384800D01*
Y373381D01*
X73615Y371533D01*
G01X80700Y377000D02*
Y378446D01*
X77963Y381183D01*
G01X70888Y394222D02*
X68963Y392297D01*
Y385293D01*
X70652Y383604D01*
Y367296D01*
X71915Y366033D01*
G01X78798Y433983D02*
X76826Y435955D01*
X72296D01*
X71894Y436357D01*
X69820D01*
X65383Y431920D01*
X58882D01*
X58028Y431066D01*
X41294D01*
X41168Y431191D01*
X41043Y431316D01*
X21152D01*
X17411Y435057D01*
X17072D01*
G01X59000Y455007D02*
X59182Y455189D01*
X69853D01*
X69897Y455233D01*
X73080D01*
X74836Y453477D01*
G01X58957Y450659D02*
X60381Y452083D01*
X68501D01*
X68807Y451777D01*
X76398D01*
X77371Y450804D01*
X77854D01*
X78754Y449904D01*
G01X70488Y465291D02*
X70059Y465720D01*
X57504D01*
X56795Y466429D01*
G01X74450Y457429D02*
X72075Y459804D01*
X69456D01*
X66005Y463255D01*
X62093D01*
X60527Y461689D01*
X52957D01*
X52936Y461668D01*
X40416D01*
X38243Y463841D01*
X33948D01*
X32548Y465241D01*
G01X70713Y461504D02*
X70019D01*
X67468Y464055D01*
X61761D01*
X61010Y463304D01*
X45394D01*
X41262Y467436D01*
G01X36237Y441728D02*
Y443161D01*
X35787Y443611D01*
X29683D01*
X29233Y443161D01*
Y439755D01*
X28783Y439305D01*
X19850D01*
X19037Y440118D01*
Y443608D01*
X19437Y444008D01*
X25622D01*
X26022Y444408D01*
Y445208D01*
X25622Y445608D01*
X19437D01*
X18915Y446130D01*
Y449033D01*
G01X55023Y443238D02*
X54582Y443679D01*
X43306D01*
X39328Y447656D01*
X35195Y451789D01*
X19365D01*
X18915Y451339D01*
Y449033D01*
G01X61038Y424878D02*
X55500Y419340D01*
X34750D01*
X33666Y418256D01*
X26493D01*
X26388Y418151D01*
X23689D01*
X22376Y416838D01*
X14657D01*
G01X90480Y437608D02*
X89580Y436708D01*
X79236D01*
X75789Y440155D01*
X73381D01*
X72178Y441357D01*
X69440D01*
X65033Y436950D01*
X61167D01*
X59209Y438908D01*
G01X70809Y438057D02*
X69909Y437157D01*
X69487D01*
X65096Y432766D01*
X43659D01*
G01X74780Y429794D02*
X72935D01*
X71409Y431320D01*
X69999D01*
X67399Y428720D01*
X60210D01*
X55630Y424140D01*
X32527D01*
X31443Y423056D01*
X24362D01*
X24357Y423051D01*
G01X37988Y438328D02*
X34820D01*
X34703Y438445D01*
X34334D01*
G01X94490Y437720D02*
X94387Y437823D01*
X93331D01*
X91846Y439308D01*
X89775D01*
X88527Y438060D01*
X79117D01*
X76423Y440754D01*
Y442476D01*
X75344Y443555D01*
X70506D01*
X67589Y440638D01*
X57545D01*
X54602Y437695D01*
X51771D01*
X49693Y439773D01*
X39534D01*
X38089Y438328D01*
X37988D01*
G01X19757Y418538D02*
X21812D01*
X23025Y419751D01*
X25725D01*
X25830Y419856D01*
X32770D01*
X33854Y420940D01*
X54695D01*
X60495Y426740D01*
X73467D01*
X74021Y427294D01*
X77093D01*
X77612Y427813D01*
X80347D01*
X82575Y430041D01*
X82681D01*
G01X78738Y429679D02*
X77215D01*
X75630Y428094D01*
X71583D01*
X71409Y427920D01*
X60542D01*
X55162Y422540D01*
X33191D01*
X32107Y421456D01*
X25167D01*
X25062Y421351D01*
X16458D01*
X16129Y421022D01*
X14719D01*
X14409Y421332D01*
X11964D01*
G01X98427Y437720D02*
X96166Y439981D01*
X92454D01*
X92327Y440108D01*
X89396D01*
X88148Y438860D01*
X79449D01*
X77223Y441086D01*
Y442808D01*
X75676Y444355D01*
X70174D01*
X67257Y441438D01*
X54519D01*
X52476Y439395D01*
G01X74656Y421838D02*
X72154Y424340D01*
X67289D01*
X65382Y422433D01*
G01X82677Y433595D02*
X80815D01*
X79503Y432283D01*
X78093D01*
X76525Y433851D01*
Y434049D01*
X75419Y435155D01*
X71964D01*
X71562Y435557D01*
X70152D01*
X65715Y431120D01*
X59214D01*
X57560Y429466D01*
X32691D01*
X32441Y429716D01*
X19323D01*
X17936Y431103D01*
G01X94490Y433783D02*
X93165Y435108D01*
X89839D01*
X88316Y433585D01*
Y433078D01*
X87321Y432083D01*
X85673D01*
X85331Y431741D01*
X81976D01*
X81718Y431483D01*
X75496D01*
X75311Y431668D01*
X72193D01*
X71741Y432120D01*
X69667D01*
X67067Y429520D01*
X59878D01*
X56098Y425740D01*
X31864D01*
X30840Y424716D01*
X28098D01*
X28063Y424751D01*
X12344D01*
X11894Y425201D01*
Y426768D01*
X12344Y427218D01*
X13850D01*
X14762Y428130D01*
Y433076D01*
X14206Y433632D01*
G01X82663Y457486D02*
Y458630D01*
X80834Y460458D01*
Y462044D01*
X79839Y463039D01*
X78985D01*
X77381Y464643D01*
Y468561D01*
X77915Y469095D01*
G01X70857Y433857D02*
X69920Y432920D01*
X69335D01*
X66735Y430320D01*
X59546D01*
X56566Y427340D01*
X31201D01*
X30177Y426316D01*
X28767D01*
X28622Y426461D01*
X19015D01*
G01X14147Y438989D02*
X14148Y438988D01*
X16673D01*
X21112Y434549D01*
X64896D01*
X70104Y439757D01*
X71514D01*
X73616Y437655D01*
X74752D01*
G01X74437Y473159D02*
X72735Y471457D01*
X70366D01*
X69492Y470583D01*
X63859D01*
X63000Y471442D01*
G01X74460Y461287D02*
Y462909D01*
X72395Y464974D01*
Y465789D01*
X71193Y466991D01*
X59486D01*
X57748Y468729D01*
X48807D01*
X45944Y471592D01*
X44156D01*
X41215Y474533D01*
G01X78793Y445704D02*
X78542Y445955D01*
X69510D01*
X67346Y443791D01*
X61110D01*
X59622Y445279D01*
X46964D01*
X46007Y446236D01*
G01X70868Y477094D02*
X68840Y475066D01*
X64880D01*
X63059Y476887D01*
X55534D01*
X51951Y480470D01*
X50778D01*
X48515Y482733D01*
G01X82542Y445403D02*
Y445492D01*
X79830Y448204D01*
X78049D01*
X77054Y449199D01*
Y449306D01*
X75383Y450977D01*
X68475D01*
X68169Y451283D01*
X62487D01*
X60063Y448859D01*
X49387D01*
X46056Y452190D01*
Y453366D01*
X42535Y456887D01*
X34821D01*
G01X98427Y433783D02*
X98372D01*
X96247Y435908D01*
X78904D01*
X75457Y439355D01*
X73049D01*
X71846Y440557D01*
X69772D01*
X65365Y436150D01*
X23847D01*
X23748Y436249D01*
G01X26611Y441743D02*
X22315D01*
G01X70909Y469595D02*
X70456Y469142D01*
X62047D01*
X57663Y473526D01*
Y473783D01*
G01X90426Y449431D02*
X88526Y447531D01*
Y445222D01*
X87007Y443703D01*
X81837D01*
X80493Y445047D01*
Y446409D01*
X79498Y447404D01*
X74806D01*
X74157Y446755D01*
X65037D01*
X64415Y446133D01*
G01X74702Y469183D02*
Y471019D01*
X76137Y472454D01*
Y473864D01*
X75740Y474261D01*
Y475624D01*
X76505Y476389D01*
Y477799D01*
X74973Y479331D01*
X74100D01*
X72851Y480580D01*
Y482572D01*
X70613Y484810D01*
G01X31517Y445328D02*
X38115D01*
G01X70868Y473157D02*
X70581D01*
X68807Y471383D01*
X66258D01*
X65300Y472341D01*
Y472395D01*
X61612Y476083D01*
X55205D01*
X52585Y478703D01*
X48209D01*
X45579Y481333D01*
X33715D01*
G01X28472Y447107D02*
X30897Y449532D01*
X31134D01*
G01X48298Y454813D02*
X50084Y453027D01*
X51425D01*
G01X58523Y443238D02*
X58770Y442991D01*
X67678D01*
X69842Y445155D01*
X76008D01*
X77843Y443320D01*
X79799D01*
X80873Y442246D01*
Y440655D01*
X81868Y439660D01*
X87279D01*
X89499Y441880D01*
X90426D01*
G01X86663Y453583D02*
X84728Y455518D01*
X82226D01*
X80963Y456781D01*
Y457859D01*
X79472Y459350D01*
X73992D01*
X72760Y460582D01*
Y462246D01*
X71415Y463591D01*
X69064D01*
X67800Y464855D01*
X61429D01*
X60703Y464129D01*
X53120D01*
X50845Y466404D01*
G01X82535Y461227D02*
X82256Y461506D01*
Y465227D01*
X80215Y467268D01*
Y474421D01*
X79379Y475257D01*
Y479067D01*
X78116Y480330D01*
Y484742D01*
X81242Y487868D01*
Y491194D01*
X76740Y495696D01*
Y498969D01*
G01X74805Y477094D02*
X73138Y478761D01*
X73104Y478794D01*
X70163D01*
X69935Y478566D01*
X58947D01*
X56041Y481472D01*
X54123D01*
X50162Y485433D01*
X41015D01*
G01X70868Y481031D02*
X69203Y479366D01*
X60652D01*
X56750Y483268D01*
X55580D01*
X53815Y485033D01*
G01X69615Y493333D02*
Y490031D01*
X74598Y485048D01*
Y485021D01*
G01X78421Y473078D02*
X79070Y473727D01*
Y474434D01*
X78579Y474925D01*
Y478735D01*
X77316Y479998D01*
Y485074D01*
X80442Y488200D01*
Y490862D01*
X73550Y497754D01*
Y503589D01*
G01X74695Y449260D02*
X73012Y447577D01*
X66466D01*
X64910Y449133D01*
X62390D01*
X60516Y447259D01*
X48724D01*
X43815Y452168D01*
Y453333D01*
X41861Y455287D01*
X36474D01*
X35774Y454587D01*
X33868D01*
X32822Y455633D01*
X26794D01*
X25225Y454064D01*
X21128D01*
X20928Y453864D01*
G01X59913Y488683D02*
X59063Y487833D01*
Y485583D01*
G01X79134Y461339D02*
X76151Y464322D01*
Y466028D01*
X74983Y467196D01*
X72874D01*
X72279Y467791D01*
X59818D01*
X55869Y471740D01*
X50676D01*
X48081Y474335D01*
Y476567D01*
G01D02*
X45523Y479125D01*
X39007D01*
X33315Y473433D01*
G01X62150Y576887D02*
X59927Y574665D01*
G02X59016Y574287I-912J911D01*
G01X56872D01*
G02X54333Y576826I0J2539D01*
G01Y578196D01*
G02X57823Y581686I3490J0D01*
G01X69541D01*
G02X71055Y581059I0J-2141D01*
G01X71565Y580549D01*
G02X72543Y578188I-2361J-2361D01*
G01Y566714D01*
G03X76200Y557885I12488J1D01*
G01X82179Y551906D01*
G02X87141Y539927I-11979J-11979D01*
G01Y515746D01*
G03X90295Y508131I10768J-1D01*
G01X90294D01*
X96818Y501607D01*
G02X98189Y498297I-3310J-3310D01*
G01Y488075D01*
G02X97600Y486653I-2011J0D01*
G01X97185Y486238D01*
G03X96485Y484548I1690J-1690D01*
G03X97599Y481860I3802J1D01*
G01X98427Y481031D01*
G01X67244Y535455D02*
X73437D01*
X74210Y536228D01*
X75702D01*
G01X63942Y534229D02*
X66018D01*
X67244Y535455D01*
G01X72677Y528615D02*
Y530123D01*
X71700Y531100D01*
X69200D01*
G01X67367Y526789D02*
Y529267D01*
X69200Y531100D01*
G01X26181Y537559D02*
X33759D01*
X36600Y540400D01*
X43500D01*
G01D02*
X43752Y540148D01*
X49565D01*
G01X44879Y522272D02*
X46923Y524316D01*
Y528179D01*
G01X26181Y517559D02*
X31322Y522700D01*
X34605D01*
X35033Y522272D01*
X44879D01*
G01X52903Y520948D02*
Y524697D01*
X49421Y528179D01*
X46923D01*
G01X74870Y488789D02*
X72156Y491503D01*
Y496692D01*
X69815Y499033D01*
G01X62250Y567387D02*
X47500D01*
G03X41200Y561087I0J-6300D01*
G01Y556771D01*
G03X43044Y552316I6300J-1D01*
G01X43394Y551966D01*
G03X47849Y550122I4454J4456D01*
G01X73736D01*
G02X76710Y548890I-1J-4208D01*
G02X77942Y545913I-2978J-2976D01*
G01X77943Y545914D01*
Y517128D01*
G03X79407Y513593I5000J0D01*
G01X93882Y499117D01*
Y499082D01*
G02X96077Y493783I-5299J-5299D01*
G01Y488762D01*
G02X95774Y488030I-1035J0D01*
G01X95160Y487416D01*
G02X94078Y486850I-1444J1444D01*
G03X93514Y486617I-1J-797D01*
G01X93199Y486301D01*
X93189D01*
X92802Y485699D01*
Y485685D01*
X92790Y485673D01*
Y484909D01*
G03X93330Y483606I1843J0D01*
G01X93475Y483461D01*
G03X93763Y483269I626J627D01*
G01X93926Y483201D01*
X93954Y483173D01*
G02X94490Y481879I-1294J-1294D01*
G01Y481031D01*
G01X62250Y563487D02*
X61381D01*
G02X60582Y563818I0J1130D01*
G02X60251Y564617I799J799D01*
G01Y565239D01*
G03X59403Y566087I-848J0D01*
G01X57600D01*
X57160Y565647D01*
X55960D01*
X55520Y566087D01*
X54320D01*
X53880Y565647D01*
X52680D01*
X52240Y566087D01*
X51040D01*
X50600Y565647D01*
X49400D01*
X48960Y566087D01*
X47500D01*
G03X42500Y561087I0J-5000D01*
G01Y556771D01*
G03X43964Y553236I5000J0D01*
G01X44314Y552886D01*
G03X47849Y551422I3535J3536D01*
G01X73735D01*
G02X77630Y549810I1J-5509D01*
G02X79243Y545913I-3898J-3896D01*
G01Y534200D01*
X79683Y533760D01*
Y532560D01*
X79243Y532120D01*
Y530920D01*
X79683Y530480D01*
Y529280D01*
X79243Y528840D01*
Y527640D01*
X79683Y527200D01*
Y526000D01*
X79243Y525560D01*
Y524360D01*
X79683Y523920D01*
Y522720D01*
X79243Y522280D01*
Y521080D01*
X79683Y520640D01*
Y519440D01*
X79243Y519000D01*
Y517128D01*
G03X80327Y514513I3699J1D01*
G01X95182Y499656D01*
Y499596D01*
G02X97377Y493784I-6599J-5813D01*
G01Y488762D01*
G02X96692Y487108I-2339J0D01*
G01X95812Y486228D01*
X95750D01*
X94490Y484968D01*
G01X63942Y537729D02*
X64246Y538033D01*
X66915D01*
X70115Y541233D01*
G01X57065Y544023D02*
X58825Y541763D01*
X63918D01*
G01D02*
X69585D01*
X70115Y541233D01*
G01X70900Y519700D02*
X70387Y519187D01*
X67065D01*
G01X60403Y524823D02*
X61937Y523289D01*
X67367D01*
G01D02*
Y521402D01*
X67065Y521100D01*
Y519187D01*
G01X51070Y530394D02*
X50064Y531400D01*
X30022D01*
X26181Y527559D01*
G01X65750Y567387D02*
X69523D01*
G01X65750Y563487D02*
Y563535D01*
G02X66114Y564414I1243J0D01*
G01X67071Y565371D01*
G02X67778Y565664I707J-706D01*
G01X68898D01*
G02X69555Y565007I0J-657D01*
G01Y564187D01*
G01X62150Y572987D02*
X56872D01*
G02X53033Y576826I0J3839D01*
G01Y578196D01*
G02X57823Y582986I4790J0D01*
G01X69541D01*
G02X71975Y581978I1J-3441D01*
G01X72485Y581468D01*
G02X73843Y578189I-3281J-3280D01*
G01Y566715D01*
G03X77120Y558804I11188J0D01*
G01X83099Y552826D01*
G02X88441Y539927I-12899J-12898D01*
G01Y515746D01*
G03X91214Y509051I9468J0D01*
G01X93709Y506556D01*
Y506555D01*
X97737Y502527D01*
G02X99489Y498297I-4229J-4229D01*
G01Y487532D01*
G02X98427Y484968I-3626J0D01*
G01X62150Y600272D02*
X57338D01*
G03X53391Y596325I0J-3947D01*
G01Y591506D01*
G03X59511Y585386I6120J0D01*
G01X70057D01*
G02X73309Y584039I0J-4599D01*
G01X75393Y581955D01*
X75394D01*
X76008Y581340D01*
G02X76992Y578964I-2376J-2376D01*
G01Y577131D01*
G03X80437Y568811I11766J-2D01*
G01X87170Y562078D01*
G02X92234Y549852I-12226J-12226D01*
G01Y517036D01*
X92235D01*
G03X95849Y508307I12343J-2D01*
G01X96218Y507939D01*
X101932Y502225D01*
G02X104062Y497083I-5142J-5142D01*
G01Y489003D01*
G02X103583Y487845I-1637J-1D01*
G01X102782Y487044D01*
G02X101889Y486674I-893J893D01*
G03X101433Y486485I0J-645D01*
G01X100944Y485996D01*
G03X100651Y485289I707J-707D01*
G01Y484413D01*
G03X101831Y481564I4029J0D01*
G01X102364Y481031D01*
G01X62150Y596372D02*
X60902D01*
G02X59970Y597304I0J932D01*
G01Y598244D01*
G03X59242Y598972I-728J0D01*
G01X57338D01*
G03X54691Y596325I0J-2647D01*
G01Y591506D01*
G03X59511Y586686I4820J0D01*
G01X70057D01*
G02X74229Y584958I1J-5899D01*
G01X75932Y583255D01*
X75934D01*
X76315Y582874D01*
X76927Y582260D01*
G02X78292Y578964I-3295J-3295D01*
G01Y577131D01*
G03X81357Y569731I10465J0D01*
G01X88090Y562998D01*
X88089D01*
G02X93534Y549852I-13145J-13145D01*
G01Y541040D01*
X93990Y540584D01*
Y538984D01*
X93534Y538528D01*
Y536928D01*
X93990Y536472D01*
Y534872D01*
X93534Y534416D01*
Y532816D01*
X93990Y532360D01*
Y530760D01*
X93534Y530304D01*
Y528704D01*
X93990Y528248D01*
Y526648D01*
X93534Y526192D01*
Y523616D01*
X94127Y523024D01*
Y521424D01*
X93534Y520832D01*
Y517036D01*
G03X96768Y509227I11043J-1D01*
G01X97136Y508860D01*
X102852Y503144D01*
G02X105362Y497084I-6062J-6061D01*
G01Y489003D01*
G02X104494Y486916I-2938J-2D01*
G01X104148Y486582D01*
X102654Y485088D01*
G02X102364Y484968I-290J290D01*
G01X62050Y605972D02*
X57160D01*
G02X53567Y609565I0J3593D01*
G01Y610525D01*
X53568D01*
G02X54810Y613522I4231J2D01*
G01X54868Y613579D01*
X58113Y616824D01*
G02X64231Y619358I6119J-6120D01*
G01X78869D01*
G02X86380Y616247I1J-10621D01*
G01X96372Y606255D01*
G02X99510Y598679I-7575J-7576D01*
G01Y516052D01*
G03X102511Y508807I10246J0D01*
G01X106322Y504996D01*
G02X108538Y499646I-5352J-5351D01*
G01Y489008D01*
G02X107691Y486962I-2895J0D01*
G01X106728Y485999D01*
G03X106301Y484968I1031J-1031D01*
G01X62050Y609872D02*
X60119Y607941D01*
X59735Y607558D01*
G02X59046Y607272I-690J689D01*
G01X57160D01*
G02X54867Y609565I0J2293D01*
G01Y610525D01*
G02X55725Y612598I2931J1D01*
G01X55779Y612651D01*
X59032Y615904D01*
G02X64232Y618058I5200J-5200D01*
G01X78869D01*
G02X85460Y615328I0J-9321D01*
G01X95453Y605335D01*
G02X98210Y598679I-6656J-6656D01*
G01Y516051D01*
G03X101591Y507888I11546J1D01*
G01X105402Y504077D01*
G02X107238Y499645I-4432J-4432D01*
G01Y489009D01*
G02X106771Y487882I-1594J0D01*
G01X104850Y485961D01*
G03X104570Y485285I676J-676D01*
G01Y484118D01*
G03X105529Y481803I3274J0D01*
G01X106301Y481031D01*
G01X65650Y600272D02*
X66569D01*
G03X69599Y601527I0J4285D01*
G01X65650Y596372D02*
X67029D01*
G03X67591Y596934I0J562D01*
G01Y598626D01*
G02X68241Y599276I650J0D01*
G01X69009D01*
G02X69569Y598716I0J-560D01*
G01Y598159D01*
G01X65650Y576887D02*
X66615Y575921D01*
G03X67423Y575587I807J808D01*
G01X67723D01*
G03X68733Y576006I-1J1429D01*
G01X69388Y576660D01*
G01X65650Y572987D02*
X66615Y573953D01*
G02X67423Y574287I807J-808D01*
G01X67723D01*
G02X69260Y573651I1J-2173D01*
G01X69450Y573460D01*
G01X65550Y605972D02*
X66206Y606628D01*
G02X69569Y608021I3363J-3363D01*
G01X65550Y609872D02*
X67122D01*
G02X67800Y609591I0J-959D01*
G03X68803Y609798I344J866D01*
G01X68841Y609836D01*
G03X69496Y611417I-1581J1581D01*
G01X69661Y591387D02*
X69933Y591659D01*
X74236D01*
X78212Y595635D01*
X81317D01*
X84015Y598333D01*
Y606633D01*
X86015Y608633D01*
G01X66579Y592250D02*
X67588Y593259D01*
X73341D01*
X80915Y600833D01*
Y601033D01*
G01X63125Y592801D02*
X61183D01*
X58715Y590333D01*
G01X62681Y589462D02*
X74119D01*
X74724Y588857D01*
G01X66201Y684703D02*
X68485D01*
G02X69451Y684303I0J-1366D01*
G01X66201Y680803D02*
X67166Y681769D01*
G02X67974Y682103I807J-808D01*
G01X68082D01*
G02X68712Y681842I0J-891D01*
G01X69451Y681103D01*
G01X62701Y690503D02*
X62087Y691117D01*
G03X60431Y691803I-1656J-1656D01*
G01X57589D01*
G02X53851Y695541I0J3738D01*
G01Y696744D01*
G02X55000Y699518I3923J0D01*
G02X57774Y700667I2774J-2774D01*
G01X69621D01*
G02X70254Y700541I0J-1653D01*
G01X70388Y700486D01*
G02X71848Y699510I-1723J-4157D01*
G01X84637Y686722D01*
G03X86899Y685784I2263J2262D01*
G01X92853D01*
G02X96955Y684086I1J-5801D01*
G01X110459Y670582D01*
G02X112157Y666480I-4103J-4101D01*
G01Y518247D01*
X112158Y518248D01*
G03X114112Y513527I6675J-2D01*
G02X115240Y511958I-4226J-4228D01*
G02X115863Y509300I-5355J-2657D01*
G01Y488817D01*
G02X114743Y486110I-3828J-2D01*
G01X114581Y485948D01*
G03X114175Y484968I980J-980D01*
G01X62701Y694403D02*
X62144Y693845D01*
G02X60351Y693103I-1792J1793D01*
G01X57589D01*
G02X55151Y695541I0J2438D01*
G01Y696744D01*
G02X55920Y698598I2623J-1D01*
G02X57774Y699367I1855J-1854D01*
G01X69621D01*
G02X69756Y699340I0J-353D01*
G01X69758Y699339D01*
X69892Y699284D01*
G02X70928Y698590I-1228J-2954D01*
G01X83717Y685802D01*
G03X86898Y684484I3182J3182D01*
G01X92853D01*
G02X96035Y683166I0J-4500D01*
G01X109539Y669662D01*
G02X110857Y666480I-3182J-3182D01*
G01Y518248D01*
G03X113192Y512607I7976J-2D01*
G02X114075Y511379I-3306J-3309D01*
G02X114563Y509299I-4190J-2080D01*
G01Y488817D01*
G02X113823Y487030I-2527J0D01*
G01X112831Y486038D01*
G03X112475Y485179I859J-859D01*
G01Y484824D01*
G03X113955Y481251I5053J0D01*
G01X114175Y481031D01*
G01X61750Y718613D02*
X61336Y718200D01*
G02X59126Y717284I-2211J2210D01*
G01X57303D01*
G03X51777Y711758I0J-5526D01*
G01Y710158D01*
G03X53475Y706056I5801J-1D01*
G01X54733Y704798D01*
G03X58835Y703100I4101J4103D01*
G01X70764D01*
G02X72532Y702368I0J-2501D01*
G01X82168Y692732D01*
G03X83936Y692000I1768J1769D01*
G01X96761D01*
G02X98529Y691268I0J-2501D01*
G01X113868Y675929D01*
G02X115186Y672747I-3182J-3182D01*
G01Y521145D01*
G03X118155Y513976I10133J-3D01*
G01X118277Y513855D01*
G02X120162Y509305I-4553J-4552D01*
G01X120161D01*
Y484971D01*
G03X121609Y481475I4944J0D01*
G01X122053Y481031D01*
G01X62701Y684703D02*
X54815D01*
Y684702D01*
G03X50422Y682881I-3J-6201D01*
G01X50382Y682839D01*
X49032Y681490D01*
G03X47140Y676920I4570J-4569D01*
G01Y675053D01*
G03X54503Y667690I7363J0D01*
G01X57839D01*
G02X60454Y666606I-1J-3699D01*
G01X101538Y625522D01*
G02X102622Y622907I-2615J-2616D01*
G01Y516458D01*
G03X105071Y510545I8364J1D01*
G01X106430Y509186D01*
Y509185D01*
X109401Y506214D01*
G02X111938Y500089I-6125J-6125D01*
G01Y488597D01*
G02X111657Y487919I-959J0D01*
G01X111227Y487489D01*
G02X110541Y487205I-686J686D01*
G01X110532D01*
G03X109735Y486875I0J-1127D01*
G01X108752Y485892D01*
G03X108438Y485134I758J-758D01*
G01Y484348D01*
G03X109511Y481759I3662J1D01*
G01X110238Y481031D01*
G01X62701Y680803D02*
X61087D01*
G02X60499Y681391I0J588D01*
G01Y682647D01*
G03X59743Y683403I-756J0D01*
G01X54815D01*
G03X51349Y681968I-1J-4901D01*
G01X51314Y681932D01*
X49952Y680570D01*
G03X48440Y676920I3650J-3650D01*
G01Y675053D01*
G03X54503Y668990I6063J0D01*
G01X57839D01*
G02X61374Y667526I0J-5000D01*
G01X75102Y653798D01*
X75724D01*
X76573Y652949D01*
Y652327D01*
X77421Y651479D01*
X78044D01*
X78892Y650630D01*
Y650008D01*
X79741Y649159D01*
X80363D01*
X81211Y648311D01*
Y647689D01*
X82060Y646840D01*
X82682D01*
X83531Y645992D01*
Y645369D01*
X102458Y626442D01*
G02X103922Y622907I-3536J-3535D01*
G01Y601040D01*
X104362Y600600D01*
Y599400D01*
X103922Y598960D01*
Y597760D01*
X104362Y597320D01*
Y596120D01*
X103922Y595680D01*
Y594480D01*
X104362Y594040D01*
Y592840D01*
X103922Y592400D01*
Y542400D01*
X104362Y541960D01*
Y540760D01*
X103922Y540320D01*
Y539120D01*
X104362Y538680D01*
Y537480D01*
X103922Y537040D01*
Y535840D01*
X104362Y535400D01*
Y534200D01*
X103922Y533760D01*
Y532560D01*
X104362Y532120D01*
Y530920D01*
X103922Y530480D01*
Y529280D01*
X104362Y528840D01*
Y527640D01*
X103922Y527200D01*
Y516459D01*
G03X105991Y511464I7064J0D01*
G01X107730Y509725D01*
Y509724D01*
X110320Y507134D01*
G02X113238Y500089I-7044J-7044D01*
G01Y488596D01*
G02X112577Y486999I-2260J0D01*
G01X110764Y485186D01*
G02X110238Y484968I-526J526D01*
G01X66201Y690503D02*
X68244D01*
G03X69451Y691003I0J1707D01*
G01X66201Y694403D02*
X67843Y692761D01*
G03X68803I480J480D01*
G03X69474Y694381I-1620J1620D01*
G01Y694403D01*
G01X65250Y718613D02*
X66145Y717718D01*
G03X67123Y717313I978J978D01*
G01X68023D01*
G03X68876Y717667I-1J1207D01*
G01X69523Y718313D01*
G01X65250Y714713D02*
X66145Y715608D01*
G02X67123Y716013I978J-978D01*
G01X68023D01*
G02X69048Y715589I1J-1449D01*
G01X69523Y715113D01*
G01X65150Y728513D02*
X66634D01*
G02X67218Y728271I0J-826D01*
G01X67236Y728253D01*
G03X68103Y727894I867J867D01*
G01X68947D01*
G03X69472Y728419I0J525D01*
G01Y729385D01*
G01X65150Y724613D02*
X65753D01*
G03X69548Y726185I0J5367D01*
G01X61750Y714713D02*
X61435Y715027D01*
G03X59126Y715984I-2309J-2307D01*
G01X57303D01*
G03X53077Y711758I0J-4226D01*
G01Y710158D01*
G03X54395Y706976I4500J0D01*
G01X55653Y705718D01*
G03X58835Y704400I3182J3182D01*
G01X70764D01*
G02X73452Y703288I1J-3802D01*
G01X74241Y702499D01*
X74864D01*
X75712Y701650D01*
Y701028D01*
X76561Y700179D01*
X77183D01*
X78031Y699331D01*
Y698709D01*
X78880Y697860D01*
X79502D01*
X80351Y697012D01*
Y696389D01*
X81199Y695541D01*
X81821D01*
X82670Y694692D01*
Y694070D01*
X83088Y693652D01*
G03X83936Y693300I849J849D01*
G01X96761D01*
G02X99449Y692188I1J-3802D01*
G01X114788Y676849D01*
G02X116486Y672747I-4103J-4101D01*
G01Y670420D01*
X116926Y669980D01*
Y668780D01*
X116486Y668340D01*
Y667140D01*
X116926Y666700D01*
Y665500D01*
X116486Y665060D01*
Y663860D01*
X116926Y663420D01*
Y662220D01*
X116486Y661780D01*
Y660580D01*
X116926Y660140D01*
Y658940D01*
X116486Y658500D01*
Y608500D01*
X116926Y608060D01*
Y606860D01*
X116486Y606420D01*
Y605220D01*
X116926Y604780D01*
Y603580D01*
X116486Y603140D01*
Y601940D01*
X116926Y601500D01*
Y600300D01*
X116486Y599860D01*
Y598660D01*
X116926Y598220D01*
Y597020D01*
X116486Y596580D01*
Y595380D01*
X116926Y594940D01*
Y593740D01*
X116486Y593300D01*
Y543300D01*
X116926Y542860D01*
Y541660D01*
X116486Y541220D01*
Y540020D01*
X116926Y539580D01*
Y538380D01*
X116486Y537940D01*
Y536740D01*
X116926Y536300D01*
Y535100D01*
X116486Y534660D01*
Y533460D01*
X116926Y533020D01*
Y531820D01*
X116486Y531380D01*
Y530180D01*
X116926Y529740D01*
Y528540D01*
X116486Y528100D01*
Y521144D01*
X116487Y521145D01*
G03X119073Y514898I8833J-2D01*
G01X119195Y514777D01*
G02X121461Y509305I-5472J-5471D01*
G01Y486397D01*
G03X122053Y484968I2021J0D01*
G01X61650Y724613D02*
X57589D01*
G02X54117Y728085I0J3472D01*
G01Y729788D01*
G02X55125Y732224I3444J1D01*
G01X57832Y734931D01*
G02X61934Y736629I4101J-4103D01*
G01X82332D01*
G02X86434Y734931I1J-5801D01*
G01X120618Y700747D01*
G02X122316Y696645I-4103J-4101D01*
G01Y522149D01*
X122317Y522150D01*
G03X124195Y517454I6805J-2D01*
G02X125161Y515122I-2332J-2332D01*
G01Y491343D01*
G02X124553Y489874I-2079J0D01*
G01X124552Y489873D01*
G03X124290Y489239I634J-633D01*
G01Y488403D01*
G03Y488379I1058J-12D01*
G01X124291D01*
G03X124442Y487858I1057J24D01*
G02X124533Y487758I-1558J-1509D01*
G02X125048Y486413I-1654J-1404D01*
G02X125052Y486309I-2406J-145D01*
G03X125337Y485621I973J0D01*
G01X125990Y484968D01*
G01X61650Y728513D02*
X59728Y726591D01*
X59511Y726373D01*
G02X58399Y725913I-1111J1112D01*
G01X57589D01*
G02X55417Y728085I0J2172D01*
G01Y729788D01*
G02X56045Y731304I2144J0D01*
G01X58752Y734011D01*
G02X61934Y735329I3182J-3182D01*
G01X82332D01*
G02X85514Y734011I0J-4500D01*
G01X119698Y699827D01*
G02X121016Y696645I-3182J-3182D01*
G01Y522150D01*
G03X123389Y516417I8105J-3D01*
G02X123860Y515280I-1137J-1137D01*
G01X123861Y515281D01*
Y491344D01*
G02X123860Y491343I-550J549D01*
G02X123633Y490794I-778J0D01*
G03X122990Y489239I1554J-1553D01*
G01Y488402D01*
G03X123428Y487034I2358J1D01*
G01X123493Y486968D01*
G02X123748Y486354I-614J-615D01*
G02X123752Y486276I-1105J-96D01*
G02Y486261I-1108J-7D01*
G02X123753Y486249I-1103J-98D01*
G03X125861Y481160I7197J0D01*
G01X125990Y481031D01*
G01X65447Y711413D02*
X66557D01*
X67930Y710040D01*
X72422D01*
X73715Y711333D01*
G01X62066Y711051D02*
X63504Y709613D01*
X66094D01*
X67267Y708440D01*
X85708D01*
X86515Y707633D01*
G01X65356Y707010D02*
X65526Y706840D01*
X76908D01*
X83715Y700033D01*
G01X61193Y706973D02*
X59275D01*
X57515Y708733D01*
G01X89300Y144600D02*
Y136500D01*
X87671Y134871D01*
X83977D01*
G01X84900Y145300D02*
X88600D01*
X89300Y144600D01*
G01X132651Y255357D02*
Y257633D01*
X138204Y263186D01*
X138598D01*
X140590Y265178D01*
Y265572D01*
X154689Y279671D01*
Y289796D01*
X156286Y291393D01*
X161963D01*
G01X142933Y251431D02*
X143685D01*
X144695Y252441D01*
X152017D01*
X155863Y248595D01*
Y242942D01*
X154508Y241587D01*
Y236883D01*
G01X138228Y260175D02*
X156644Y278591D01*
Y288331D01*
X157146Y288833D01*
X161963D01*
G01Y245333D02*
X159028D01*
X157463Y246898D01*
Y249258D01*
X152680Y254041D01*
X139200D01*
X136572Y251413D01*
X136427D01*
G01D02*
X136572Y251268D01*
X137434D01*
X144273Y244429D01*
Y236883D01*
G01X137809Y247647D02*
X137855D01*
X141713Y243789D01*
Y236883D01*
G01X135592Y257933D02*
X135787Y258128D01*
X142410D01*
X142810Y258528D01*
Y259749D01*
X143260Y260199D01*
X143960D01*
X144410Y259749D01*
Y258528D01*
X144810Y258128D01*
X145610D01*
X146010Y258528D01*
Y263052D01*
X146460Y263502D01*
X147160D01*
X147610Y263052D01*
Y258528D01*
X148010Y258128D01*
X148810D01*
X149210Y258528D01*
Y262929D01*
X149660Y263379D01*
X150360D01*
X150810Y262929D01*
Y258528D01*
X151210Y258128D01*
X152010D01*
X152410Y258528D01*
Y263031D01*
X152860Y263481D01*
X153560D01*
X154010Y263031D01*
Y258528D01*
X154410Y258128D01*
X161963D01*
G01X116566Y254205D02*
X125811D01*
X139158Y240858D01*
Y236883D01*
G01X119242Y252107D02*
X119459Y251890D01*
X124939D01*
X136598Y240231D01*
Y236883D01*
G01X121685Y249741D02*
X128918Y242508D01*
Y236883D01*
G01X121741Y246341D02*
X121730Y246330D01*
X126363Y241697D01*
Y236883D01*
G01D02*
Y229748D01*
X125600Y228985D01*
G01X122572Y258147D02*
X120267D01*
X119510Y257390D01*
X116924D01*
X113563Y254029D01*
Y236883D01*
G01X111008D02*
Y242830D01*
G01X130567Y258051D02*
X135186Y262670D01*
X135275D01*
X137392Y264787D01*
X137936D01*
X138990Y265841D01*
Y266235D01*
X148834Y276079D01*
Y284832D01*
G01X106504Y243329D02*
X103328Y240153D01*
Y236883D01*
G01X102713Y242975D02*
X102233D01*
X100768Y241510D01*
Y236883D01*
G01X108652Y247260D02*
X104255D01*
X98213Y241218D01*
Y236883D01*
G01X100415Y246679D02*
X95653Y241917D01*
Y236883D01*
G01X126611Y258265D02*
Y258318D01*
X124572Y260357D01*
X117628D01*
X106880Y249609D01*
X100799D01*
X94448Y243258D01*
X91418D01*
X87973Y239813D01*
Y236883D01*
G01X87200Y222000D02*
X86550Y222650D01*
Y225900D01*
G01X84863Y229783D02*
X85418Y230338D01*
Y236883D01*
G01X86550Y225900D02*
Y228096D01*
X84863Y229783D01*
G01X134529Y264470D02*
X134382D01*
X133956Y264044D01*
X130492D01*
X126733Y267803D01*
Y274900D01*
X126363Y275270D01*
Y297283D01*
G01X137190Y266587D02*
X133590D01*
X132647Y265644D01*
X131155D01*
X128763Y268036D01*
Y278790D01*
X128918Y278945D01*
Y297283D01*
G01X131901Y267444D02*
Y268553D01*
X130363Y270091D01*
Y278127D01*
X130808Y278572D01*
Y283738D01*
X136598Y289528D01*
Y297283D01*
G01X132163Y271041D02*
Y275329D01*
X133508Y276674D01*
Y284175D01*
X139158Y289825D01*
Y297283D01*
G01X137690Y273752D02*
Y283522D01*
X144273Y290105D01*
Y297283D01*
G01X79189Y235119D02*
X80953Y236883D01*
X82858D01*
G01X92682Y331571D02*
X87115D01*
G01X82858Y297283D02*
Y313236D01*
X83258Y313636D01*
X86073D01*
X86473Y314036D01*
Y314836D01*
X86073Y315236D01*
X83258D01*
X82858Y315636D01*
Y316436D01*
X83258Y316836D01*
X86073D01*
X86473Y317236D01*
Y318036D01*
X86073Y318436D01*
X83258D01*
X82858Y318836D01*
Y319636D01*
X83258Y320036D01*
X89886D01*
X90336Y320486D01*
Y321186D01*
X89886Y321636D01*
X83258D01*
X82858Y322036D01*
Y322836D01*
X83258Y323236D01*
X90035D01*
X90485Y323686D01*
Y324386D01*
X90035Y324836D01*
X83258D01*
X82858Y325236D01*
Y326036D01*
X83258Y326436D01*
X90283D01*
X90733Y326886D01*
Y327586D01*
X90283Y328036D01*
X83432D01*
X82982Y328486D01*
Y331121D01*
X83432Y331571D01*
X87115D01*
G01X116123Y297283D02*
Y303593D01*
X113713Y306003D01*
G01D02*
Y310083D01*
X113749Y310119D01*
G01D02*
X117701D01*
X119615Y312033D01*
G01X119603Y285731D02*
X102235D01*
X101163Y286803D01*
X92614D01*
X85418Y293999D01*
Y297283D01*
G01X781514Y334665D02*
X773699D01*
G02X771200Y335700I0J3534D01*
G03X770097Y336157I-1103J-1103D01*
G01X764683D01*
G03X759521Y334019I0J-7300D01*
G01X743005Y317503D01*
G02X738903Y315805I-4101J4103D01*
G01X149442D01*
G02X145598Y317397I1J5438D01*
G01X105327Y357668D01*
G02X99163Y372549I14881J14881D01*
G01Y393400D01*
X99162D01*
Y393401D01*
G02X99551Y395383I5244J0D01*
G02X100014Y396144I3750J-1760D01*
G03X100576Y397800I-2159J1656D01*
G02X101000Y399500I3620J0D01*
G01X101358Y399858D01*
G03X102364Y402287I-2429J2429D01*
G01X106301Y398350D02*
G03X106213Y398138I211J-212D01*
G01Y372250D01*
G03X107531Y369068I4500J0D01*
G01X151508Y325091D01*
G03X154690Y323773I3182J3182D01*
G01X158100D01*
X158540Y324213D01*
X159740D01*
X160180Y323773D01*
X161380D01*
X161820Y324213D01*
X163020D01*
X163460Y323773D01*
X164660D01*
X165100Y324213D01*
X166300D01*
X166740Y323773D01*
X167940D01*
X168380Y324213D01*
X169580D01*
X170020Y323773D01*
X171220D01*
X171660Y324213D01*
X172860D01*
X173300Y323773D01*
X223300D01*
X223740Y324213D01*
X224940D01*
X225380Y323773D01*
X226580D01*
X227020Y324213D01*
X228220D01*
X228660Y323773D01*
X229860D01*
X230300Y324213D01*
X231500D01*
X231940Y323773D01*
X233140D01*
X233580Y324213D01*
X234780D01*
X235220Y323773D01*
X236420D01*
X236860Y324213D01*
X238060D01*
X238500Y323773D01*
X288500D01*
X288940Y324213D01*
X290140D01*
X290580Y323773D01*
X291780D01*
X292220Y324213D01*
X293420D01*
X293860Y323773D01*
X295060D01*
X295500Y324213D01*
X296700D01*
X297140Y323773D01*
X298340D01*
X298780Y324213D01*
X299980D01*
X300420Y323773D01*
X301620D01*
X302060Y324213D01*
X303260D01*
X303700Y323773D01*
X353700D01*
X354140Y324213D01*
X355340D01*
X355780Y323773D01*
X356980D01*
X357420Y324213D01*
X358620D01*
X359060Y323773D01*
X360260D01*
X360700Y324213D01*
X361900D01*
X362340Y323773D01*
X730651D01*
G03X732913Y324711I-1J3200D01*
G01X759536Y351334D01*
G02X763638Y353032I4101J-4103D01*
G01X770065D01*
G03X772281Y353950I0J3134D01*
G02X773247Y354350I966J-966D01*
G01X781514D01*
G01X106301Y402287D02*
X105838Y401824D01*
G03X104600Y398834I2990J-2989D01*
G01Y397477D01*
G03X104763Y397083I557J0D01*
G02X104913Y396721I-362J-362D01*
G01Y372250D01*
G03X106611Y368148I5801J-1D01*
G01X150588Y324171D01*
G03X154690Y322473I4101J4103D01*
G01X730652D01*
G03X733833Y323791I-1J4500D01*
G01X760456Y350414D01*
G02X763638Y351732I3182J-3182D01*
G01X770300D01*
G02X772117Y350980I1J-2569D01*
G03X773481Y350415I1364J1364D01*
G01X781514D01*
G01Y338605D02*
X772561D01*
G03X771100Y338000I0J-2066D01*
G02X769789Y337457I-1311J1311D01*
G01X764680D01*
G03X758601Y334939I0J-8597D01*
G01X742085Y318423D01*
G02X738903Y317105I-3182J3182D01*
G01X360200D01*
X359705Y317600D01*
X358600D01*
X358105Y317105D01*
X356955D01*
X356515Y317545D01*
X355315D01*
X354875Y317105D01*
X353675D01*
X353235Y317545D01*
X352035D01*
X351595Y317105D01*
X301595D01*
X301155Y317545D01*
X299955D01*
X299515Y317105D01*
X298315D01*
X297875Y317545D01*
X296675D01*
X296235Y317105D01*
X295035D01*
X294595Y317545D01*
X293395D01*
X292955Y317105D01*
X291755D01*
X291315Y317545D01*
X290115D01*
X289675Y317105D01*
X288475D01*
X288035Y317545D01*
X286835D01*
X286395Y317105D01*
X236395D01*
X235955Y317545D01*
X234755D01*
X234315Y317105D01*
X233115D01*
X232675Y317545D01*
X231475D01*
X231035Y317105D01*
X229835D01*
X229395Y317545D01*
X228195D01*
X227755Y317105D01*
X226555D01*
X226115Y317545D01*
X224915D01*
X224475Y317105D01*
X223275D01*
X222835Y317545D01*
X221635D01*
X221195Y317105D01*
X171195D01*
X170755Y317545D01*
X169555D01*
X169115Y317105D01*
X167915D01*
X167475Y317545D01*
X166275D01*
X165835Y317105D01*
X164635D01*
X164195Y317545D01*
X162995D01*
X162555Y317105D01*
X161355D01*
X160915Y317545D01*
X159715D01*
X159275Y317105D01*
X158075D01*
X157635Y317545D01*
X156435D01*
X155995Y317105D01*
X149443D01*
G02X146518Y318316I-1J4136D01*
G01X146517Y318318D01*
X106247Y358588D01*
G02X100463Y372550I13960J13962D01*
G01Y393312D01*
G02X100742Y394860I3943J89D01*
G02X100873Y395099I2555J-1245D01*
G03X102364Y398350I-12810J7842D01*
G01X110238Y402287D02*
X109951Y402001D01*
G03X108163Y397683I4318J-4317D01*
G01Y396677D01*
G02X107996Y396274I-570J0D01*
G03X107338Y394682I1593J-1590D01*
G01Y393508D01*
G03X108142Y391565I2751J1D01*
G01X108143D01*
X108144Y391564D01*
G02X108613Y390430I-1133J-1133D01*
G01Y374601D01*
G03X110311Y370499I5801J-1D01*
G01X119607Y361203D01*
X146805Y334006D01*
X147131Y333679D01*
G03X159701Y328473I12569J12569D01*
G01X719456D01*
G03X722637Y329791I-1J4500D01*
G01X758937Y366091D01*
G02X762119Y367409I3182J-3182D01*
G01X770817D01*
G02X772154Y366855I0J-1891D01*
G03X773820Y366165I1666J1666D01*
G01X781514D01*
G01X114175Y402287D02*
G03X112345Y397869I4418J-4418D01*
G01Y384615D01*
G03X118762Y369120I21913J-2D01*
G01X142748Y345134D01*
G03X162692Y336873I19944J19944D01*
G01X705136D01*
G03X708317Y338191I-1J4500D01*
G01X759910Y389784D01*
G02X763092Y391102I3182J-3182D01*
G01X770204D01*
G02X770938Y390798I0J-1038D01*
G01X771010Y390726D01*
G02X771357Y390443I-1240J-1874D01*
G03X772946Y389785I1589J1589D01*
G01X781514D01*
G01X110238Y398350D02*
X110099Y398210D01*
G03X109463Y396676I1534J-1535D01*
G02X108916Y395355I-1870J1D01*
G03X108638Y394683I673J-672D01*
G01Y393509D01*
G03X109063Y392483I1451J0D01*
G02X109913Y390431I-2052J-2052D01*
G01Y374601D01*
G03X111231Y371419I4500J0D01*
G01X147725Y334925D01*
X148051Y334598D01*
G03X159701Y329773I11649J11650D01*
G01X165400D01*
X165840Y330213D01*
X167040D01*
X167480Y329773D01*
X168680D01*
X169120Y330213D01*
X170320D01*
X170760Y329773D01*
X171960D01*
X172400Y330213D01*
X173600D01*
X174040Y329773D01*
X175240D01*
X175680Y330213D01*
X176880D01*
X177320Y329773D01*
X178520D01*
X178960Y330213D01*
X180160D01*
X180600Y329773D01*
X230600D01*
X231040Y330213D01*
X232240D01*
X232680Y329773D01*
X233880D01*
X234320Y330213D01*
X235520D01*
X235960Y329773D01*
X237160D01*
X237600Y330213D01*
X238800D01*
X239240Y329773D01*
X240440D01*
X240880Y330213D01*
X242080D01*
X242520Y329773D01*
X243720D01*
X244160Y330213D01*
X245360D01*
X245800Y329773D01*
X295800D01*
X296240Y330213D01*
X297440D01*
X297880Y329773D01*
X299080D01*
X299520Y330213D01*
X300720D01*
X301160Y329773D01*
X302360D01*
X302800Y330213D01*
X304000D01*
X304440Y329773D01*
X305640D01*
X306080Y330213D01*
X307280D01*
X307720Y329773D01*
X308920D01*
X309360Y330213D01*
X310560D01*
X311000Y329773D01*
X361000D01*
X361440Y330213D01*
X362640D01*
X363080Y329773D01*
X364280D01*
X364720Y330213D01*
X365920D01*
X366360Y329773D01*
X719455D01*
G03X721717Y330711I-1J3200D01*
G01X758017Y367011D01*
G02X762119Y368709I4101J-4103D01*
G01X770090D01*
G03X771488Y369288I1J1975D01*
G01X771604Y369405D01*
G02X773284Y370100I1679J-1680D01*
G01X781514D01*
G01X114175Y398350D02*
G03X113645Y397070I1280J-1280D01*
G01Y384615D01*
G03X119682Y370040I20612J0D01*
G01X143668Y346054D01*
X143667Y346053D01*
G03X162691Y338173I19024J19025D01*
G01X165900D01*
X166340Y338613D01*
X167540D01*
X167980Y338173D01*
X169180D01*
X169620Y338613D01*
X170820D01*
X171260Y338173D01*
X172460D01*
X172900Y338613D01*
X174100D01*
X174540Y338173D01*
X175740D01*
X176180Y338613D01*
X177380D01*
X177820Y338173D01*
X179020D01*
X179460Y338613D01*
X180660D01*
X181100Y338173D01*
X231100D01*
X231540Y338613D01*
X232740D01*
X233180Y338173D01*
X234380D01*
X234820Y338613D01*
X236020D01*
X236460Y338173D01*
X237660D01*
X238100Y338613D01*
X239300D01*
X239740Y338173D01*
X240940D01*
X241380Y338613D01*
X242580D01*
X243020Y338173D01*
X296300D01*
X296740Y338613D01*
X297940D01*
X298380Y338173D01*
X299580D01*
X300020Y338613D01*
X301220D01*
X301660Y338173D01*
X302860D01*
X303300Y338613D01*
X304500D01*
X304940Y338173D01*
X306140D01*
X306580Y338613D01*
X307780D01*
X308220Y338173D01*
X361500D01*
X361940Y338613D01*
X363140D01*
X363580Y338173D01*
X364780D01*
X365220Y338613D01*
X366420D01*
X366860Y338173D01*
X368060D01*
X368500Y338613D01*
X369700D01*
X370140Y338173D01*
X371340D01*
X371780Y338613D01*
X372980D01*
X373420Y338173D01*
X705135D01*
G03X707397Y339111I-1J3200D01*
G01X758990Y390704D01*
G02X763092Y392402I4101J-4103D01*
G01X770324D01*
G03X771648Y392951I0J1871D01*
G01X771649D01*
X772007Y393308D01*
G02X773000Y393720I994J-993D01*
G01X781514D01*
G01X84958Y305933D02*
Y305590D01*
X87973Y302575D01*
Y297283D01*
G01X124478Y280855D02*
Y283402D01*
X120324Y287556D01*
X103127D01*
X102280Y288403D01*
X93923D01*
X87973Y294353D01*
Y297283D01*
G01X95202Y290958D02*
X95653Y291409D01*
Y297283D01*
G01X100315Y305033D02*
X100015D01*
X98213Y303231D01*
Y297283D01*
G01X98565Y290455D02*
X98213Y290807D01*
Y297283D01*
G01X102107Y290439D02*
Y290797D01*
X100768Y292136D01*
Y297283D01*
G01X105603Y291092D02*
X103328Y293367D01*
Y297283D01*
G01X110808Y291075D02*
X111008Y291275D01*
Y297283D01*
G01X114915Y290203D02*
X113513D01*
X112782Y290934D01*
Y291931D01*
X113563Y292712D01*
Y297283D01*
G01X128918Y307533D02*
Y297283D01*
G01X141315Y305433D02*
Y303733D01*
X141713Y303335D01*
Y297283D01*
G01X135308Y276806D02*
Y283712D01*
X141713Y290117D01*
Y297283D01*
G01X139784Y276432D02*
X140319Y276967D01*
Y282719D01*
X151953Y294353D01*
Y297283D01*
G01X142241Y278783D02*
Y282263D01*
X151161Y291183D01*
X151343D01*
X154508Y294348D01*
Y297283D01*
G01X94369Y425977D02*
Y425215D01*
X92854Y423700D01*
Y421206D01*
X93849Y420211D01*
X94586D01*
X95963Y418834D01*
Y417424D01*
X95927Y417388D01*
Y409124D01*
X97573Y407478D01*
X99294D01*
X99938Y406834D01*
Y399447D01*
X97821Y397330D01*
G01X94554Y421911D02*
X96833Y419632D01*
Y414909D01*
X96727Y414803D01*
Y409456D01*
X97905Y408278D01*
X99860D01*
X100214Y407924D01*
X103069D01*
X104599Y406394D01*
Y405521D01*
X105596Y404524D01*
X108506D01*
X110315Y406333D01*
G01X85721Y385798D02*
X84763Y386756D01*
Y391168D01*
X84116Y391815D01*
Y397431D01*
X84363Y397678D01*
Y399088D01*
X82745Y400706D01*
X81958D01*
X80855Y401809D01*
Y406993D01*
X82750Y408888D01*
Y411862D01*
X84159Y413271D01*
Y414974D01*
X84823Y415638D01*
Y418648D01*
X85818Y419643D01*
X87426D01*
X89086Y417983D01*
X90563D01*
G01X141595Y421932D02*
Y420220D01*
X139982Y418607D01*
Y405575D01*
X141570Y403987D01*
X146570D01*
X146743Y403814D01*
X150193D01*
X151283Y402724D01*
Y393109D01*
X156465Y387927D01*
X162126D01*
X162876Y388677D01*
X170798D01*
X174085Y385390D01*
X181660D01*
X182707Y386437D01*
X225664D01*
X227385Y388158D01*
X270340D01*
X299330Y417148D01*
G01X141682Y417902D02*
X143249Y416335D01*
X146032D01*
X147495Y414872D01*
Y405994D01*
X148875Y404614D01*
X150525D01*
X152083Y403056D01*
Y393441D01*
X156797Y388727D01*
X161794D01*
X162544Y389477D01*
X171771D01*
X172720Y388528D01*
X174131D01*
X177326Y391723D01*
X178736D01*
X180678Y389781D01*
Y389672D01*
X181752Y388598D01*
X225562D01*
X226722Y389758D01*
X267325D01*
X281729Y404162D01*
Y404514D01*
X291453Y414238D01*
G01X82459Y413976D02*
Y412703D01*
X81950Y412194D01*
Y409242D01*
X80055Y407347D01*
Y401477D01*
X80963Y400569D01*
Y397678D01*
X81802Y396839D01*
Y389111D01*
X81535Y388844D01*
G01X92913Y401383D02*
Y397283D01*
G01D02*
Y397033D01*
X90566Y394686D01*
Y394383D01*
G01X82763Y417750D02*
X80759Y415746D01*
Y409183D01*
X79255Y407679D01*
Y399849D01*
X80062Y399042D01*
Y395045D01*
X79502Y394485D01*
G01X97000Y389200D02*
X95867Y390333D01*
X93263D01*
G01D02*
X89163D01*
G01D02*
X86783Y392713D01*
X85911D01*
X84916Y393708D01*
Y396236D01*
X85163Y396483D01*
Y399906D01*
X82663Y402406D01*
G01X133864Y402287D02*
X133405Y401828D01*
G03X131863Y398105I3723J-3723D01*
G01Y397779D01*
G02X131564Y397057I-1021J0D01*
G03X130963Y395232I2472J-1825D01*
G01Y391905D01*
X130964D01*
G03X136479Y378584I18837J-3D01*
G01X139179Y375885D01*
X149397Y365667D01*
G03X152579Y364349I3182J3182D01*
G01X433585D01*
G03X436767Y365667I0J4500D01*
G01X527283Y456183D01*
G02X530465Y457501I3182J-3182D01*
G01X660749D01*
G02X662166Y456914I0J-2004D01*
G01X94076Y411204D02*
X92276Y413004D01*
Y415003D01*
X91481Y415798D01*
X88523D01*
X86772Y414047D01*
G01X98138Y405728D02*
X94076Y409790D01*
Y411204D01*
G01X122053Y402287D02*
G03X120021Y397903I4964J-4964D01*
G02X119678Y396749I-2110J-1D01*
G03X118899Y394868I1881J-1881D01*
G01X118913Y394851D01*
X118835Y394268D01*
G03X118809Y393868I2977J-394D01*
G01Y387871D01*
G03X127429Y367060I29430J-1D01*
G01X127428D01*
X142340Y352149D01*
X142986Y351502D01*
G03X162854Y343273I19866J19866D01*
G01X692770D01*
G03X695951Y344591I-1J4500D01*
G01X756894Y405534D01*
G02X760076Y406852I3182J-3182D01*
G01X770417D01*
G02X772006Y406194I0J-2248D01*
G03X773596Y405535I1590J1589D01*
G01X781514D01*
G01X133864Y398350D02*
G02X133310Y397012I-1893J0D01*
G01X132783Y396485D01*
G03X132264Y395232I1253J-1253D01*
G01X132263Y395233D01*
Y395005D01*
X132264D01*
Y394025D01*
X132263Y393951D01*
Y391905D01*
G03X137399Y379504I17537J-1D01*
G01X140099Y376805D01*
X150317Y366587D01*
G03X152579Y365649I2263J2262D01*
G01X433585D01*
G03X435847Y366587I-1J3200D01*
G01X526363Y457103D01*
G02X530465Y458801I4101J-4103D01*
G01X659400D01*
G03X661230Y459559I0J2588D01*
G01X661760Y460089D01*
G01X92014Y405439D02*
X89511Y407942D01*
X86321D01*
X84500Y409763D01*
G01D02*
X84959Y410222D01*
Y414642D01*
X86523Y416206D01*
Y417943D01*
G01X137801Y398350D02*
G03X136964Y396329I2021J-2021D01*
G01Y387568D01*
G03X137902Y385303I3203J0D01*
G01X144174Y379031D01*
X148719Y374485D01*
X148721D01*
X150940Y372266D01*
G03X154122Y370948I3182J3182D01*
G01X431384D01*
G03X434566Y372266I0J4500D01*
G01X535433Y473133D01*
G02X538615Y474451I3182J-3182D01*
G01X556107D01*
X556555Y474900D01*
X557755D01*
X558203Y474451D01*
X559403D01*
X559851Y474900D01*
X561051D01*
X561499Y474451D01*
X562699D01*
X563147Y474900D01*
X564347D01*
X564795Y474451D01*
X565995D01*
X566443Y474900D01*
X567643D01*
X568091Y474451D01*
X569291D01*
X569739Y474900D01*
X570939D01*
X571387Y474451D01*
X643900D01*
G03X644373Y474507I1J2018D01*
G03X645327Y475042I-473J1962D01*
G01X646246Y475961D01*
G01X122053Y398350D02*
G03X121446Y397393I1823J-1828D01*
G02X120896Y396065I-1878J0D01*
G03X120219Y394693I1683J-1683D01*
G01X120203Y394681D01*
X120124Y394095D01*
G03X120109Y393868I1688J-226D01*
G01Y387871D01*
G03X128348Y367980I28130J0D01*
G01X143260Y353068D01*
X143906Y352421D01*
G03X162853Y344573I18947J18947D01*
G01X168200D01*
X168640Y345013D01*
X169840D01*
X170280Y344573D01*
X171480D01*
X171920Y345013D01*
X173120D01*
X173560Y344573D01*
X174760D01*
X175200Y345013D01*
X176400D01*
X176840Y344573D01*
X178040D01*
X178480Y345013D01*
X179680D01*
X180120Y344573D01*
X181320D01*
X181760Y345013D01*
X182960D01*
X183400Y344573D01*
X233400D01*
X233840Y345013D01*
X235040D01*
X235480Y344573D01*
X236680D01*
X237120Y345013D01*
X238320D01*
X238760Y344573D01*
X239960D01*
X240400Y345013D01*
X241600D01*
X242040Y344573D01*
X243240D01*
X243680Y345013D01*
X244880D01*
X245320Y344573D01*
X298600D01*
X299040Y345013D01*
X300240D01*
X300680Y344573D01*
X301880D01*
X302320Y345013D01*
X303520D01*
X303960Y344573D01*
X305160D01*
X305600Y345013D01*
X306800D01*
X307240Y344573D01*
X308440D01*
X308880Y345013D01*
X310080D01*
X310520Y344573D01*
X363800D01*
X364240Y345013D01*
X365440D01*
X365880Y344573D01*
X367080D01*
X367520Y345013D01*
X368720D01*
X369160Y344573D01*
X370360D01*
X370800Y345013D01*
X372000D01*
X372440Y344573D01*
X373640D01*
X374080Y345013D01*
X375280D01*
X375720Y344573D01*
X692769D01*
G03X695031Y345511I-1J3200D01*
G01X755974Y406454D01*
G02X760076Y408152I4101J-4103D01*
G01X770828D01*
G03X772185Y408714I0J1919D01*
G02X774010Y409470I1825J-1825D01*
G01X781514D01*
G01X137801Y402287D02*
G03X135664Y397128I5159J-5159D01*
G01Y387568D01*
G03X136982Y384383I4504J-2D01*
G01X138958Y382408D01*
X147800Y373565D01*
X148180Y373185D01*
X148182D01*
X150020Y371346D01*
G03X154122Y369648I4101J4103D01*
G01X431384D01*
G03X435486Y371346I1J5801D01*
G01X536353Y472213D01*
G02X538615Y473151I2263J-2262D01*
G01X645546D01*
G02X646794Y472634I0J-1765D01*
G01X125990Y402287D02*
X125025Y401321D01*
G03X124263Y399483I1838J-1839D01*
G01Y398983D01*
G02X123656Y397516I-2074J-1D01*
G01X123632Y397493D01*
G03X122801Y395483I2007J-2007D01*
G01X122800D01*
Y391605D01*
G03X131666Y370198I30274J-1D01*
G01X144131Y357733D01*
G03X160628Y350900I16496J16496D01*
G01X681499D01*
G03X684681Y352218I0J4500D01*
G01X753745Y421282D01*
G02X756927Y422600I3182J-3182D01*
G01X770381D01*
G02X771950Y421950I0J-2219D01*
G01X772150Y421750D01*
G03X773285Y421280I1135J1135D01*
G01X781514D01*
G01X125990Y398350D02*
G02X125750Y397769I-821J-1D01*
G01X124663Y396683D01*
X124550Y396571D01*
G03X124100Y395483I1088J-1087D01*
G01Y391605D01*
G03X132586Y371118I28973J0D01*
G01X133299Y370405D01*
X145051Y358652D01*
G03X160628Y352200I15577J15577D01*
G01X170380D01*
X170820Y352640D01*
X172020D01*
X172460Y352200D01*
X173660D01*
X174100Y352640D01*
X175300D01*
X175740Y352200D01*
X176940D01*
X177380Y352640D01*
X178580D01*
X179020Y352200D01*
X180220D01*
X180660Y352640D01*
X181860D01*
X182300Y352200D01*
X232300D01*
X232740Y352640D01*
X233940D01*
X234380Y352200D01*
X235580D01*
X236020Y352640D01*
X237220D01*
X237660Y352200D01*
X238860D01*
X239300Y352640D01*
X240500D01*
X240940Y352200D01*
X242140D01*
X242580Y352640D01*
X243780D01*
X244220Y352200D01*
X245420D01*
X245860Y352640D01*
X247060D01*
X247500Y352200D01*
X297500D01*
X297940Y352640D01*
X299140D01*
X299580Y352200D01*
X300780D01*
X301220Y352640D01*
X302420D01*
X302860Y352200D01*
X304060D01*
X304500Y352640D01*
X305700D01*
X306140Y352200D01*
X307340D01*
X307780Y352640D01*
X308980D01*
X309420Y352200D01*
X362700D01*
X363140Y352640D01*
X364340D01*
X364780Y352200D01*
X365980D01*
X366420Y352640D01*
X367620D01*
X368060Y352200D01*
X369260D01*
X369700Y352640D01*
X370900D01*
X371340Y352200D01*
X372540D01*
X372980Y352640D01*
X374180D01*
X374620Y352200D01*
X681499D01*
G03X683761Y353138I-1J3200D01*
G01X752825Y422202D01*
G02X756927Y423900I4101J-4103D01*
G01X770281D01*
G03X771850Y424550I0J2219D01*
G02X773468Y425220I1618J-1618D01*
G01X781514D01*
G01X129927Y402287D02*
X129298Y401658D01*
G03X128107Y398783I2875J-2875D01*
G01Y383878D01*
G03X129805Y379776I5801J-1D01*
G01X149436Y360145D01*
G03X153538Y358447I4101J4103D01*
G01X671650D01*
G03X675750Y360145I-1J5801D01*
G01X753014Y437409D01*
G02X755276Y438347I2263J-2262D01*
G01X771502D01*
G02X772523Y437924I0J-1444D01*
G03X774681Y437030I2158J2158D01*
G01X781514D01*
G01X129927Y398350D02*
G03X129407Y397095I1255J-1255D01*
G01Y383878D01*
G03X130725Y380696I4500J0D01*
G01X150356Y361065D01*
G03X153538Y359747I3182J3182D01*
G01X156500D01*
X156940Y360187D01*
X158140D01*
X158580Y359747D01*
X159780D01*
X160220Y360187D01*
X161420D01*
X161860Y359747D01*
X163060D01*
X163500Y360187D01*
X164700D01*
X165140Y359747D01*
X166340D01*
X166780Y360187D01*
X167980D01*
X168420Y359747D01*
X169620D01*
X170060Y360187D01*
X171260D01*
X171700Y359747D01*
X221700D01*
X222140Y360187D01*
X223340D01*
X223780Y359747D01*
X224980D01*
X225420Y360187D01*
X226620D01*
X227060Y359747D01*
X228260D01*
X228700Y360187D01*
X229900D01*
X230340Y359747D01*
X231540D01*
X231980Y360187D01*
X233180D01*
X233620Y359747D01*
X286900D01*
X287340Y360187D01*
X288540D01*
X288980Y359747D01*
X290180D01*
X290620Y360187D01*
X291820D01*
X292260Y359747D01*
X293460D01*
X293900Y360187D01*
X295100D01*
X295540Y359747D01*
X296740D01*
X297180Y360187D01*
X298380D01*
X298820Y359747D01*
X352100D01*
X352540Y360187D01*
X353740D01*
X354180Y359747D01*
X355380D01*
X355820Y360187D01*
X357020D01*
X357460Y359747D01*
X358660D01*
X359100Y360187D01*
X360300D01*
X360740Y359747D01*
X361940D01*
X362380Y360187D01*
X363630D01*
X364070Y359747D01*
X365297D01*
X365700Y360150D01*
X366947D01*
X367350Y359747D01*
X671649D01*
G03X674830Y361065I-1J4500D01*
G01X752094Y438329D01*
G02X755276Y439647I3182J-3182D01*
G01X771355D01*
G03X772272Y440027I0J1297D01*
G02X774537Y440965I2265J-2265D01*
G01X781514D01*
G01X82663Y398383D02*
X83316Y397730D01*
Y391483D01*
X83835Y390964D01*
Y384979D01*
X81946Y383090D01*
G01X141738Y402287D02*
X141140Y401689D01*
G03X139783Y398413I3276J-3276D01*
G02X139366Y397303I-2411J272D01*
G02X139342Y397269I-1984J1375D01*
G03X138500Y395133I2288J-2136D01*
G01Y390764D01*
G03X140198Y386662I5801J-1D01*
G01X151742Y375118D01*
G03X155844Y373420I4101J4103D01*
G01X429156D01*
G03X433258Y375118I1J5801D01*
G01X555822Y497682D01*
G02X559004Y499000I3182J-3182D01*
G01X732164D01*
G02X733012Y498648I-1J-1201D01*
G01X744956Y486704D01*
G03X747644Y485592I2687J2690D01*
G01X770677D01*
G02X772267Y484934I1J-2248D01*
G01X772383Y484817D01*
G03X773691Y484275I1308J1307D01*
G01X781514D01*
G01X141738Y398350D02*
G02X141369Y397459I-1260J0D01*
G01X140336Y396426D01*
G03X139800Y395132I1294J-1294D01*
G01Y390764D01*
G03X141118Y387582I4500J0D01*
G01X152662Y376038D01*
G03X155844Y374720I3182J3182D01*
G01X429157D01*
G03X432338Y376038I-1J4500D01*
G01X554902Y498602D01*
G02X559004Y500300I4101J-4103D01*
G01X565780D01*
X566220Y500740D01*
X567420D01*
X567860Y500300D01*
X569060D01*
X569500Y500740D01*
X570700D01*
X571140Y500300D01*
X572340D01*
X572780Y500740D01*
X573980D01*
X574420Y500300D01*
X575620D01*
X576060Y500740D01*
X577260D01*
X577700Y500300D01*
X627700D01*
X628140Y500740D01*
X629340D01*
X629780Y500300D01*
X630980D01*
X631420Y500740D01*
X632620D01*
X633060Y500300D01*
X634260D01*
X634700Y500740D01*
X635900D01*
X636340Y500300D01*
X637540D01*
X637980Y500740D01*
X639180D01*
X639620Y500300D01*
X640820D01*
X641260Y500740D01*
X642460D01*
X642900Y500300D01*
X692900D01*
X693340Y500740D01*
X694540D01*
X694980Y500300D01*
X696180D01*
X696620Y500740D01*
X697820D01*
X698260Y500300D01*
X699460D01*
X699900Y500740D01*
X701100D01*
X701540Y500300D01*
X702740D01*
X703180Y500740D01*
X704380D01*
X704820Y500300D01*
X732164D01*
G02X733932Y499568I0J-2501D01*
G01X745876Y487624D01*
G03X747644Y486892I1768J1769D01*
G01X752680D01*
X753120Y487332D01*
X754320D01*
X754760Y486892D01*
X755960D01*
X756400Y487332D01*
X757600D01*
X758040Y486892D01*
X759240D01*
X759680Y487332D01*
X760880D01*
X761320Y486892D01*
X762520D01*
X762960Y487332D01*
X764160D01*
X764600Y486892D01*
X771570D01*
G03X772304Y487196I0J1038D01*
G02X774752Y488210I2448J-2448D01*
G01X781514D01*
G01Y539390D02*
X773542D01*
G02X772122Y539978I0J2009D01*
G03X770701Y540567I-1421J-1420D01*
G01X751503D01*
G03X750655Y540215I1J-1201D01*
G01X717052Y506612D01*
G02X714364Y505500I-2687J2690D01*
G01X558364D01*
G03X556102Y504562I1J-3200D01*
G01X430395Y378855D01*
G02X426293Y377157I-4101J4103D01*
G01X155500D01*
G02X153444Y378008I-1J2907D01*
G01X152926Y378527D01*
X144759Y386694D01*
G02X143705Y389240I2548J2546D01*
G01Y397500D01*
G02X145563Y401984I6342J-1D01*
G01X145865Y402287D01*
G01X781514Y543330D02*
X774161D01*
G03X772116Y542483I0J-2892D01*
G02X770629Y541867I-1487J1487D01*
G01X765300D01*
X764860Y542307D01*
X763660D01*
X763220Y541867D01*
X762020D01*
X761580Y542307D01*
X760380D01*
X759940Y541867D01*
X758740D01*
X758300Y542307D01*
X757100D01*
X756660Y541867D01*
X755460D01*
X755020Y542307D01*
X753820D01*
X753380Y541867D01*
X751503D01*
G03X749735Y541135I0J-2501D01*
G01X716132Y507532D01*
G02X714364Y506800I-1768J1769D01*
G01X710515D01*
X710075Y507240D01*
X708875D01*
X708435Y506800D01*
X707235D01*
X706795Y507240D01*
X705595D01*
X705155Y506800D01*
X704000D01*
X703600Y507200D01*
X702200D01*
X701800Y506800D01*
X648595D01*
X648155Y507240D01*
X646955D01*
X646515Y506800D01*
X645315D01*
X644875Y507240D01*
X643675D01*
X643235Y506800D01*
X642035D01*
X641595Y507240D01*
X640395D01*
X639955Y506800D01*
X638755D01*
X638315Y507240D01*
X637115D01*
X636675Y506800D01*
X635475D01*
X635035Y507240D01*
X633835D01*
X633395Y506800D01*
X583395D01*
X582955Y507240D01*
X581755D01*
X581315Y506800D01*
X580115D01*
X579675Y507240D01*
X578475D01*
X578035Y506800D01*
X576835D01*
X576395Y507240D01*
X575195D01*
X574755Y506800D01*
X573555D01*
X573115Y507240D01*
X571915D01*
X571475Y506800D01*
X570275D01*
X569835Y507240D01*
X568635D01*
X568195Y506800D01*
X558363D01*
G03X555182Y505482I1J-4500D01*
G01X429475Y379775D01*
G02X426294Y378457I-3182J3182D01*
G01X155500D01*
G02X154365Y378927I0J1605D01*
G01X152881Y380412D01*
X145679Y387614D01*
G02X145005Y389241I1627J1627D01*
G01Y396274D01*
G02X145120Y397090I2936J2D01*
G02X145865Y398350I2820J-817D01*
G01X149488Y402114D02*
X148831Y401458D01*
G03X147565Y398400I3058J-3057D01*
G01Y398004D01*
G02X147052Y396766I-1751J0D01*
G03X146431Y394662I3251J-2103D01*
G01Y390753D01*
G03X147491Y388191I3623J-1D01*
G01X151871Y383811D01*
G03X155053Y382493I3182J3182D01*
G01X421015D01*
G03X424197Y383811I0J4500D01*
G01X611273Y570887D01*
G02X614455Y572205I3182J-3182D01*
G01X770412D01*
G02X771322Y571828I0J-1287D01*
G03X774079Y570885I2756J3557D01*
G01X781514D01*
G01X149583Y398383D02*
G02X149014Y397009I-1943J0D01*
G01X148485Y396480D01*
G03X147732Y394662I1819J-1818D01*
G01X147731Y394663D01*
Y394381D01*
G03Y394356I1813J-13D01*
G01Y390752D01*
G03X148411Y389111I2322J1D01*
G01X152791Y384731D01*
G03X155053Y383793I2263J2262D01*
G01X421015D01*
G03X423277Y384731I-1J3200D01*
G01X565589Y527043D01*
Y527666D01*
X566438Y528514D01*
X567060D01*
X567909Y529363D01*
Y529985D01*
X568757Y530833D01*
X569379D01*
X570228Y531682D01*
Y532304D01*
X571076Y533153D01*
X571699D01*
X572547Y534001D01*
Y534623D01*
X573396Y535472D01*
X574018D01*
X610353Y571807D01*
G02X614455Y573505I4101J-4103D01*
G01X622780D01*
X623220Y573945D01*
X624420D01*
X624860Y573505D01*
X626060D01*
X626500Y573945D01*
X627700D01*
X628140Y573505D01*
X629340D01*
X629780Y573945D01*
X630980D01*
X631420Y573505D01*
X632620D01*
X633060Y573945D01*
X634260D01*
X634700Y573505D01*
X684700D01*
X685140Y573945D01*
X686340D01*
X686780Y573505D01*
X687980D01*
X688420Y573945D01*
X689620D01*
X690060Y573505D01*
X691260D01*
X691700Y573945D01*
X692900D01*
X693340Y573505D01*
X694540D01*
X694980Y573945D01*
X696180D01*
X696620Y573505D01*
X697820D01*
X698260Y573945D01*
X699460D01*
X699900Y573505D01*
X749900D01*
X750340Y573945D01*
X751540D01*
X751980Y573505D01*
X753180D01*
X753620Y573945D01*
X754820D01*
X755260Y573505D01*
X756460D01*
X756900Y573945D01*
X758100D01*
X758540Y573505D01*
X759740D01*
X760180Y573945D01*
X761380D01*
X761820Y573505D01*
X770488D01*
G03X771261Y573825I0J1093D01*
G02X774089Y574825I2828J-3499D01*
G01X781514D01*
G01X145663Y441483D02*
Y440783D01*
X143763Y438883D01*
Y435752D01*
X141811Y433800D01*
G01X157322Y453385D02*
X155300Y455407D01*
X148001D01*
X146090Y457318D01*
G01X145567Y453547D02*
X143708Y455406D01*
Y458134D01*
X143527Y458315D01*
Y466021D01*
X141715Y467833D01*
G01X149799Y448876D02*
X146470D01*
X145763Y449583D01*
G01X149576Y465497D02*
Y466828D01*
X151263Y468515D01*
Y469925D01*
X150268Y470920D01*
X148880D01*
X147375Y472425D01*
Y473862D01*
X145782Y475455D01*
Y477006D01*
G01X98334Y429754D02*
Y425952D01*
X98215Y425833D01*
G01X149563Y469220D02*
X148569D01*
X146569Y471220D01*
X143130D01*
X139117Y475233D01*
X134515D01*
X134215Y475533D01*
G01X151538Y853750D02*
X150262D01*
G03X149696Y853184I0J-566D01*
G01Y852325D01*
G02X148881Y851510I-815J0D01*
G01X145430D01*
G02X142248Y852828I0J4500D01*
G01X141074Y854002D01*
G02X139757Y857184I3183J3181D01*
G01X139756Y857183D01*
Y862519D01*
G02X139878Y863129I1586J0D01*
G01X139880Y863131D01*
X140123Y863717D01*
G02X140956Y864551I1425J-590D01*
G01X141545Y864795D01*
G02X142147Y864915I603J-1454D01*
G01X173687D01*
G02X176868Y863597I-1J-4500D01*
G01X187575Y852890D01*
G02X188893Y849708I-3182J-3182D01*
G01Y781516D01*
G02X187575Y778334I-4500J0D01*
G01X141368Y732127D01*
G03X140050Y728945I3182J-3182D01*
G01Y532890D01*
G03X141592Y529166I5268J0D01*
G02X142342Y528245I-4108J-4111D01*
G02X143294Y525057I-4860J-3187D01*
G01X143295Y525058D01*
Y518612D01*
G02X141499Y514276I-6132J0D01*
G03X139484Y508135I8353J-6142D01*
G01Y491385D01*
G02X139078Y490405I-1386J0D01*
G03X138738Y489174I2056J-1230D01*
G01Y488744D01*
G03X139503Y486896I2615J0D01*
G01X139504Y486895D01*
G02X139786Y486214I-681J-681D01*
G01Y485214D01*
G03X141364Y481406I5386J1D01*
G01X141738Y481031D01*
G01X151611Y850210D02*
X145430D01*
G02X141328Y851908I-1J5801D01*
G01X140154Y853082D01*
G02X138456Y857184I4103J4101D01*
G01Y862519D01*
G02X138707Y863697I2886J1D01*
G01X138922Y864215D01*
G02X140458Y865752I2626J-1088D01*
G01X141047Y865996D01*
G02X142146Y866215I1100J-2655D01*
G01X173686D01*
G02X177788Y864517I1J-5801D01*
G01X188495Y853810D01*
G02X190193Y849708I-4103J-4101D01*
G01Y781516D01*
G02X188495Y777414I-5801J-1D01*
G01X142288Y731207D01*
G03X141350Y728945I2262J-2263D01*
G01Y532889D01*
X141351Y532890D01*
G03X142512Y530086I3967J0D01*
G02X144595Y525057I-5029J-5029D01*
G01Y518612D01*
G02X142493Y513433I-7432J0D01*
G01X142494Y513432D01*
G03X140784Y508134I7357J-5300D01*
G01Y491384D01*
G02X140145Y489644I-2687J-1D01*
G03X140121Y489589I992J-465D01*
G01X140082Y489492D01*
G03X140423Y487816I1437J-580D01*
G02X141149Y486063I-1753J-1753D01*
G01Y486015D01*
G03X141738Y484968I2163J527D01*
G01X98433Y449125D02*
X99963Y447595D01*
Y445987D01*
X101979Y443971D01*
X106380D01*
X108063Y442288D01*
Y438988D01*
X107963Y438888D01*
Y436878D01*
X106968Y435883D01*
X103806D01*
X102508Y434585D01*
G01X150490Y840895D02*
X149343D01*
G03X148333Y839885I0J-1010D01*
G01Y839063D01*
G02X147665Y838395I-668J0D01*
G01X146881D01*
G02Y843999I0J2802D01*
G01X156993D01*
G03X158223Y844229I4J3382D01*
G01X158901Y844494D01*
G02X159600Y844626I699J-1787D01*
G01X175706D01*
G02X178888Y843307I-1J-4500D01*
G01X183754Y838440D01*
G02X185072Y835258I-3182J-3182D01*
G01Y785431D01*
G02X184134Y783169I-3200J1D01*
G01X135996Y735031D01*
G03X134298Y730929I4103J-4101D01*
G01Y530440D01*
G03X135314Y527986I3472J0D01*
G02X135617Y527565I-1132J-1134D01*
G02X135784Y526853I-1435J-712D01*
G01Y484714D01*
G03X136962Y481870I4022J0D01*
G01X137801Y481031D01*
G01X102600Y425983D02*
X104400Y427783D01*
X117165D01*
X117915Y427033D01*
G01X150690Y837095D02*
X146881D01*
G02Y845299I0J4102D01*
G01X156995D01*
G03X157751Y845441I0J2082D01*
G01X158428Y845705D01*
G02X159599Y845926I1172J-2998D01*
G01X175707D01*
G02X179808Y844227I-1J-5801D01*
G01X184674Y839360D01*
G02X186372Y835258I-4103J-4101D01*
G01Y785430D01*
G02X185054Y782249I-4500J1D01*
G01X136916Y734111D01*
G03X135598Y730929I3182J-3182D01*
G01Y530441D01*
G03X136234Y528906I2171J0D01*
G02X137084Y526854I-2052J-2052D01*
G01Y486094D01*
G03X137373Y485396I987J0D01*
G01X137801Y484968D01*
G01X150801Y832781D02*
X147311D01*
G03X145162Y831892I-1J-3039D01*
G01X143265Y829995D01*
G03X142006Y826953I3042J-3041D01*
G01Y826852D01*
G03X143194Y823982I4058J-1D01*
G03X146062Y822795I2867J2868D01*
G01X161965D01*
G02X165146Y821477I-1J-4500D01*
G01X177934Y808689D01*
G02X179251Y805507I-3183J-3181D01*
G01X179252Y805508D01*
Y788062D01*
G02X178314Y785800I-3200J1D01*
G01X130944Y738430D01*
X130942D01*
G03X129244Y734328I4103J-4101D01*
G01Y531070D01*
G03X130873Y527136I5565J0D01*
G02X131552Y526192I-2541J-2544D01*
G02X131927Y524594I-3221J-1599D01*
G01Y491762D01*
G02X131539Y490825I-1325J0D01*
G01X131538Y490824D01*
G03X130864Y489193I1631J-1629D01*
G01Y487871D01*
G03X131493Y486352I2148J0D01*
G02X131895Y485609I-1048J-1047D01*
G02X131927Y485304I-1450J-306D01*
G03X133579Y481316I5640J0D01*
G01X133864Y481031D01*
G01X94414Y445605D02*
X96461Y443558D01*
X99452D01*
X102388Y440622D01*
G01X150801Y828981D02*
X149383D01*
G02X148722Y829642I0J661D01*
G01Y830793D01*
G03X148034Y831481I-688J0D01*
G01X147311D01*
G03X146082Y830972I0J-1738D01*
G01X144185Y829075D01*
G03X143306Y826953I2122J-2122D01*
G01Y826852D01*
G03X144114Y824902I2757J0D01*
G03X146062Y824095I1948J1948D01*
G01X161964D01*
G02X166066Y822397I1J-5801D01*
G01X178854Y809609D01*
G02X180552Y805507I-4103J-4101D01*
G01Y803262D01*
X180992Y802822D01*
Y801622D01*
X180552Y801182D01*
Y799982D01*
X180992Y799542D01*
Y798342D01*
X180552Y797902D01*
Y796702D01*
X180992Y796262D01*
Y795062D01*
X180552Y794622D01*
Y793422D01*
X180992Y792982D01*
Y791782D01*
X180552Y791342D01*
Y790142D01*
X180992Y789702D01*
Y788502D01*
X180552Y788062D01*
G02X179234Y784880I-4500J0D01*
G01X143224Y748870D01*
Y748250D01*
X142375Y747401D01*
X141753D01*
X140905Y746553D01*
Y745930D01*
X140056Y745082D01*
X139434D01*
X138585Y744233D01*
Y743611D01*
X137737Y742763D01*
X137115D01*
X136266Y741914D01*
Y741292D01*
X135418Y740443D01*
X134795D01*
X133947Y739595D01*
Y738973D01*
X133098Y738124D01*
X132476D01*
X131862Y737510D01*
G03X130544Y734328I3182J-3182D01*
G01Y531071D01*
G03X131793Y528056I4264J0D01*
G02X133227Y524594I-3462J-3462D01*
G01Y491762D01*
G02X132459Y489905I-2626J-1D01*
G01X132458D01*
G03X132344Y489768I712J-708D01*
G03X132164Y489191I835J-577D01*
G01Y487870D01*
X132165Y487871D01*
G03X132413Y487272I847J0D01*
G02X133167Y485877I-1969J-1966D01*
G03X133317Y485515I512J0D01*
G01X133864Y484968D01*
G01X86568Y445669D02*
X85068Y447169D01*
Y450088D01*
X86063Y451083D01*
X87700D01*
X89163Y452546D01*
Y460698D01*
X88962Y460899D01*
Y462309D01*
X89265Y462612D01*
Y465975D01*
X90413Y467123D01*
X90612D01*
X92131Y468642D01*
Y470006D01*
X93819Y471694D01*
X97411D01*
X101111Y475394D01*
X104306D01*
X106050Y477138D01*
G01X90426Y441880D02*
Y445444D01*
X90815Y445833D01*
G01X781514Y633880D02*
X772586D01*
G02X771278Y634422I0J1849D01*
G01X771162Y634539D01*
G03X769572Y635197I-1589J-1590D01*
G01X291059D01*
G03X254916Y620226I0J-51114D01*
G01X152135Y517445D01*
G03X147912Y507250I10195J-10195D01*
G01Y485595D01*
G02X147375Y484299I-1833J0D01*
G01Y484263D01*
X146758Y483647D01*
G03X145675Y481031I2616J-2615D01*
G01X781514Y637815D02*
X773047D01*
G03X771456Y637156I0J-2250D01*
G02X769865Y636497I-1591J1591D01*
G01X360700D01*
X360297Y636900D01*
X359250D01*
X358847Y636497D01*
X357618D01*
X357178Y636937D01*
X355978D01*
X355538Y636497D01*
X354338D01*
X353898Y636937D01*
X352698D01*
X352258Y636497D01*
X302258D01*
X301858Y636897D01*
X300858D01*
X300458Y636497D01*
X299458D01*
X299058Y636897D01*
X298058D01*
X297658Y636497D01*
X296658D01*
X296258Y636897D01*
X295258D01*
X294858Y636497D01*
X293858D01*
X293458Y636897D01*
X292458D01*
X292058Y636497D01*
X291058D01*
G03X253997Y621146I1J-52414D01*
G01Y621147D01*
X151215Y518365D01*
G03X146612Y507250I11115J-11114D01*
G01Y486918D01*
G02X145896Y485188I-2446J-1D01*
G01X145675Y484968D01*
G01X257015Y394833D02*
X247596D01*
X245721Y392958D01*
X220308D01*
X219148Y391798D01*
X202796D01*
X199817Y394777D01*
X184707D01*
X183541Y393611D01*
X165433D01*
X165099Y393944D01*
X162832Y396211D01*
X160708D01*
X160106Y396813D01*
X156706D01*
X155054Y398465D01*
Y402623D01*
X151828Y405849D01*
Y410323D01*
X151062Y411089D01*
Y414656D01*
X147641Y418077D01*
X145737D01*
G01X141738Y429846D02*
X143975Y427609D01*
X146380D01*
X147912Y426077D01*
Y425204D01*
X149444Y423672D01*
X154254D01*
X155249Y422677D01*
Y421267D01*
X154901Y420919D01*
Y417392D01*
X154751Y417242D01*
Y413112D01*
X160750Y407113D01*
X162181D01*
X163127Y406167D01*
X179681D01*
X180539Y405310D01*
X183600D01*
X184621Y406331D01*
X220561D01*
X223171Y408941D01*
X229695D01*
X237576Y416822D01*
Y417080D01*
G01X82732Y453139D02*
X83988Y451883D01*
X87368D01*
X88363Y452878D01*
Y457988D01*
X86705Y459646D01*
X86066D01*
X85035Y460677D01*
Y464963D01*
X84489Y465509D01*
X84459Y465540D01*
Y471019D01*
X85521Y472081D01*
Y476171D01*
X85237Y476455D01*
Y484937D01*
X85871Y485571D01*
G01X83021Y473118D02*
Y473879D01*
X80979Y475921D01*
Y477799D01*
X82716Y479536D01*
Y493542D01*
X81029Y495229D01*
G01X86735Y461382D02*
X88465Y463112D01*
Y468377D01*
X88659Y468571D01*
Y469980D01*
X90048Y471369D01*
X91055D01*
X94386Y474700D01*
X95200D01*
G01X86937Y477160D02*
Y483368D01*
X88567Y484998D01*
Y497381D01*
X88215Y497733D01*
G01X82759Y469436D02*
X82780Y469457D01*
Y470472D01*
X84721Y472413D01*
Y473960D01*
X84379Y474302D01*
Y477799D01*
X83516Y478662D01*
Y497509D01*
X79160Y501865D01*
Y504249D01*
G01X145663Y445583D02*
X149463Y441783D01*
X149563D01*
G01X145675Y429846D02*
X147375Y431546D01*
X154254D01*
X155786Y430014D01*
Y429141D01*
X157318Y427609D01*
X158191D01*
X159357Y426443D01*
Y425381D01*
X159970Y424768D01*
Y417456D01*
X161301Y416125D01*
X161671D01*
X163154Y414642D01*
Y414267D01*
X165039Y412382D01*
X166507D01*
X166829Y412060D01*
X181660D01*
X182800Y413200D01*
X191952D01*
X198651Y419899D01*
X216281D01*
X224015Y427633D01*
G01X142008Y457429D02*
Y457655D01*
X140127Y459536D01*
Y462685D01*
X134163Y468649D01*
Y469043D01*
G01X91167Y488144D02*
Y484600D01*
X90501Y483934D01*
Y480516D01*
G01X86959Y469276D02*
Y471255D01*
X87121Y471417D01*
Y472245D01*
X89645Y474769D01*
X90632D01*
X92076Y476213D01*
Y477623D01*
X90501Y479198D01*
Y480516D01*
G01X90965Y465270D02*
X92931Y467236D01*
Y469674D01*
X94151Y470894D01*
X99429D01*
X100169Y471634D01*
X103582D01*
X105945Y473997D01*
X106279D01*
X108538Y476256D01*
Y477799D01*
X110070Y479331D01*
X116713D01*
X117815Y480433D01*
G01X152286Y817740D02*
G03X148761Y819200I-3525J-3525D01*
G01X142982D01*
G03X138880Y817502I-1J-5801D01*
G01X127181Y805803D01*
G03X125483Y801701I4103J-4101D01*
G01Y523266D01*
G03X126667Y520408I4042J0D01*
G02X127672Y519009I-3766J-3766D01*
G02X128227Y516642I-4771J-2367D01*
G01Y484377D01*
G03X129391Y481567I3974J0D01*
G01X129927Y481031D01*
G01X152286Y814140D02*
X151242D01*
G02X150089Y815293I0J1153D01*
G01Y817019D01*
G03X149239Y817869I-850J0D01*
G01X149237D01*
G03X148762Y817900I-477J-3654D01*
G01X142982D01*
G03X139800Y816582I0J-4500D01*
G01Y815960D01*
X138951Y815111D01*
X138329D01*
X137481Y814263D01*
Y813640D01*
X136632Y812792D01*
X136010D01*
X135161Y811943D01*
Y811321D01*
X134313Y810473D01*
X133691D01*
X132842Y809624D01*
Y809002D01*
X131994Y808153D01*
X131371D01*
X130523Y807305D01*
Y806683D01*
X129674Y805834D01*
X129052D01*
X128101Y804883D01*
G03X126783Y801701I3182J-3182D01*
G01Y751600D01*
X127223Y751160D01*
Y749960D01*
X126783Y749520D01*
Y748320D01*
X127223Y747880D01*
Y746680D01*
X126783Y746240D01*
Y745040D01*
X127223Y744600D01*
Y743400D01*
X126783Y742960D01*
Y741760D01*
X127223Y741320D01*
Y740120D01*
X126783Y739680D01*
Y738480D01*
X127223Y738040D01*
Y736840D01*
X126783Y736400D01*
Y523267D01*
G03X127587Y521328I2742J1D01*
G02X128837Y519587I-4687J-4684D01*
G02X129527Y516643I-5936J-2944D01*
G01Y485934D01*
G03X129927Y484968I1366J0D01*
G01X86663Y457283D02*
X84235Y459711D01*
Y464631D01*
X81059Y467807D01*
Y474709D01*
X80179Y475589D01*
Y481373D01*
X80416Y481610D01*
G01X86765Y465205D02*
Y467065D01*
X85259Y468571D01*
Y470687D01*
X86321Y471749D01*
Y474139D01*
X88637Y476455D01*
Y477865D01*
X88163Y478339D01*
Y483462D01*
X89367Y484666D01*
Y493897D01*
X90515Y495045D01*
Y498686D01*
X87189Y502012D01*
X84549D01*
G01X98286Y465448D02*
X98084Y465650D01*
X94500D01*
G01D02*
Y468838D01*
X94844Y469182D01*
G01X125853Y473129D02*
X125800D01*
Y473130D01*
X124431D01*
X122234Y470933D01*
X118163D01*
G01D02*
X104268D01*
X102469Y469134D01*
G01X106149Y457371D02*
X110050Y461272D01*
Y461812D01*
G01X107363Y450233D02*
X107963Y450833D01*
Y454188D01*
X106149Y456002D01*
Y457371D01*
G01X91198Y595087D02*
X93012D01*
X95136Y592963D01*
G01X91123Y591887D02*
X89615Y593395D01*
Y593659D01*
X87148Y596126D01*
G01X91223Y588487D02*
X91149Y588561D01*
X84952D01*
X84752Y588361D01*
G01X90878Y585185D02*
X85501Y579808D01*
X84951D01*
G01X85654Y659044D02*
X85710Y659100D01*
X89400D01*
G01X83960Y632636D02*
X82696Y633900D01*
X80200D01*
G01X90746Y712435D02*
X90977Y712204D01*
X93627D01*
X97296Y715873D01*
G01X90947Y709040D02*
X91326Y708661D01*
X95647D01*
X97047Y707261D01*
G01X91003Y705214D02*
X92125Y704092D01*
X107786D01*
G01X91130Y701741D02*
X97682D01*
X99706Y699717D01*
G01X201237Y106350D02*
X203125Y108238D01*
X216415D01*
G01X254498Y88487D02*
X252052Y90933D01*
X238065D01*
X220760Y108238D01*
X216415D01*
G01X152663Y272053D02*
X153442D01*
X154572Y270923D01*
X161963D01*
G01Y260683D02*
X166878D01*
X171016Y256545D01*
X172508D01*
X179215Y263252D01*
X187879D01*
X188590Y262541D01*
G01D02*
X192284Y258847D01*
G01X150666Y243134D02*
X151953Y241847D01*
Y236883D01*
G01X161963Y255568D02*
X169729D01*
X170353Y254945D01*
X176427D01*
X176915Y255433D01*
G01X195698Y259749D02*
Y259715D01*
X193030Y257047D01*
X184459D01*
X183599Y257907D01*
X179389D01*
X176915Y255433D01*
G01X188115Y253008D02*
X161963D01*
G01X196365Y256414D02*
X196269D01*
X192863Y253008D01*
X188115D01*
G01X159768Y238444D02*
Y240578D01*
X161963Y242773D01*
G01X174561Y261545D02*
Y261417D01*
X171762Y258618D01*
Y258345D01*
G01X167894Y243024D02*
X166463Y244455D01*
Y246323D01*
X164898Y247888D01*
X161963D01*
G01X173665Y244229D02*
X169099D01*
X167894Y243024D01*
G01X160004Y233894D02*
X157068Y236830D01*
Y236883D01*
G01X161963Y273483D02*
X169183D01*
X169800Y274100D01*
G01X173650Y273900D02*
X173450Y274100D01*
X169800D01*
G01X161963Y250448D02*
X169715D01*
G01X181278Y247707D02*
X178537Y250448D01*
X169715D01*
G01X171061Y261545D02*
X169363Y263243D01*
X161963D01*
G01X171105Y265687D02*
X171061Y265643D01*
Y261545D01*
G01X161963Y281158D02*
X167312D01*
X168487Y282333D01*
X172815D01*
X177216Y286734D01*
X185042D01*
G01D02*
Y286860D01*
X187615Y289433D01*
G01X161963Y286278D02*
X164898D01*
X167051Y288431D01*
Y293752D01*
G01D02*
Y294151D01*
X170800Y297900D01*
G01X161963Y278598D02*
X167015D01*
X169150Y280733D01*
X173515D01*
X177744Y284962D01*
X184399D01*
X184427Y284934D01*
X187533D01*
X188273Y285674D01*
G01D02*
X188874D01*
X191615Y282933D01*
G01X161963Y276038D02*
X166718D01*
X169813Y279133D01*
X177215D01*
G01X187118Y281963D02*
X184288Y279133D01*
X177215D01*
G01X154508Y297283D02*
Y303226D01*
X156515Y305233D01*
G01X163142Y294193D02*
Y302355D01*
X162692Y302805D01*
X157518D01*
X157068Y302355D01*
Y297283D01*
G01X161963Y283718D02*
X166400D01*
X167515Y284833D01*
X170315D01*
G01X176558Y289824D02*
X173617Y286883D01*
X172365D01*
X170315Y284833D01*
G01X176514Y294017D02*
X171924D01*
X170596Y292689D01*
G01X172818Y288683D02*
X170596Y290905D01*
Y292689D01*
G01X149498Y406396D02*
X150281Y405613D01*
X150658D01*
X154254Y402017D01*
Y398133D01*
X156374Y396013D01*
X156501Y395885D01*
X158279D01*
X159274Y394890D01*
Y394309D01*
X160772Y392811D01*
X186997D01*
X189610Y390198D01*
X224899D01*
X226059Y391358D01*
X265955D01*
X279629Y405032D01*
G01X153549Y421972D02*
X151501Y419924D01*
Y415349D01*
X151862Y414988D01*
Y414494D01*
X155978Y410378D01*
Y405628D01*
X157352Y404254D01*
X162204D01*
X163199Y403259D01*
Y401644D01*
X164764Y400079D01*
X166037D01*
X167155Y398961D01*
Y397852D01*
X169336Y395671D01*
X181457D01*
X183764Y397978D01*
X198514D01*
X199513Y398977D01*
X217649D01*
X219949Y396677D01*
X224589D01*
X224590Y396678D01*
X234241D01*
X236114Y398551D01*
Y398552D01*
X237462Y399900D01*
X246348D01*
X257400Y410952D01*
X265534D01*
X286988Y432406D01*
X290615D01*
G01X153587Y406496D02*
X155854Y404229D01*
Y401546D01*
X156849Y400551D01*
X161321D01*
X162941Y398931D01*
Y398365D01*
X166229Y395077D01*
X166436Y394871D01*
X182537D01*
X184044Y396378D01*
X205124D01*
X207806Y393696D01*
X218783D01*
X219645Y394558D01*
X234600D01*
X237978Y397936D01*
X248436D01*
X249300Y398800D01*
G01X267673Y429991D02*
X261341Y423659D01*
X256618D01*
X252400Y419441D01*
X243241D01*
X235700Y411900D01*
Y409454D01*
X233587Y407341D01*
X223834D01*
X221224Y404731D01*
X185421D01*
X184400Y403710D01*
X181673D01*
X180409Y402446D01*
X179944Y401982D01*
X179763Y401967D01*
X177457D01*
X175100Y404324D01*
X163837D01*
X161848Y406313D01*
X157698D01*
G01X161475Y410299D02*
X162375Y409399D01*
X162463D01*
X163680Y408182D01*
X176331D01*
X178219Y410070D01*
X182400D01*
X182939Y409531D01*
X218979D01*
X235705Y426257D01*
X251539D01*
X253615Y428333D01*
G01X210042Y412265D02*
X211355Y413578D01*
X216477D01*
X217637Y412418D01*
X219603D01*
X236278Y429093D01*
X242093D01*
X245000Y432000D01*
G01X258100Y452100D02*
Y451000D01*
X237793Y430693D01*
X235615D01*
X221258Y416336D01*
X202628D01*
X197684Y411392D01*
X182392D01*
X182000Y411000D01*
X166757D01*
X166175Y411582D01*
X162776D01*
X162359Y411999D01*
X160987D01*
X159163Y413823D01*
Y422588D01*
X157599Y424152D01*
X156838D01*
X155786Y425204D01*
Y426077D01*
X154254Y427609D01*
X151312D01*
X149612Y425909D01*
G01X165337Y414489D02*
X166308Y415460D01*
X178300D01*
X178710Y415870D01*
X181514D01*
X181984Y415400D01*
X191889D01*
X197989Y421500D01*
X214700D01*
X237493Y444293D01*
X239656D01*
X249474Y454111D01*
Y454474D01*
X253500Y458500D01*
G01X157463Y421883D02*
Y421739D01*
X155701Y419977D01*
Y416500D01*
X155551Y416350D01*
Y413444D01*
X160396Y408599D01*
X162131D01*
X163625Y407105D01*
X179876D01*
X180871Y406110D01*
X182281D01*
X184102Y407931D01*
X219642D01*
X235311Y423600D01*
X240400D01*
G01X267479Y420536D02*
X261095Y414152D01*
X253000D01*
X241948Y403100D01*
X238788D01*
X238787Y403101D01*
X236137D01*
X232914Y399878D01*
X223264D01*
X223263Y399877D01*
X221275D01*
X218975Y402177D01*
X181273D01*
X180975Y401879D01*
X180550Y401455D01*
X180273Y401178D01*
X179954D01*
X179612Y400836D01*
X168592D01*
X167409Y402019D01*
X165229D01*
G01X251100Y408500D02*
X244100Y401500D01*
X238125D01*
X238124Y401501D01*
X236800D01*
X234514Y399215D01*
Y399214D01*
X233578Y398278D01*
X223927D01*
X223926Y398277D01*
X220612D01*
X218312Y400577D01*
X180804D01*
X180605Y400378D01*
X180286D01*
X179486Y399578D01*
X175765D01*
X173864Y397677D01*
G01X177182Y467018D02*
X178880D01*
X178962Y466936D01*
X183070D01*
G01X175477Y472360D02*
X178951D01*
X179790Y471521D01*
X191710D01*
X194083Y469148D01*
G01X176815Y479061D02*
X176970D01*
X178427Y477604D01*
X187706D01*
X188616Y476694D01*
G01X161473Y457213D02*
X161956D01*
X163508Y455661D01*
X165922D01*
X166187Y455926D01*
X169570D01*
X172522Y458878D01*
X176402D01*
X180081Y462557D01*
X187021D01*
G01X165360Y477094D02*
X165760D01*
X168260Y479594D01*
X168889D01*
X171586Y482291D01*
Y487414D01*
X169917Y489083D01*
G01X149594Y480923D02*
G03X151320Y485090I-4167J4167D01*
G01Y485641D01*
G02X151751Y486682I1472J0D01*
G01X151798Y486729D01*
G03X152612Y488697I-1969J1967D01*
G01Y499821D01*
G02X157804Y512357I17728J1D01*
G01X157940Y512492D01*
X247720Y602272D01*
G02X288226Y619050I40506J-40506D01*
G01X770099D01*
G02X771210Y618590I0J-1572D01*
G03X772321Y618130I1111J1112D01*
G01X781514D01*
G01X200453Y439066D02*
X199948Y438561D01*
Y438465D01*
X197885Y436402D01*
G01X157560Y445484D02*
X159361Y443683D01*
X160819D01*
X164569Y439933D01*
X178098D01*
X178300Y440135D01*
G01X153549Y449535D02*
X155786Y447298D01*
X162128D01*
X163258Y446168D01*
Y445090D01*
X166115Y442233D01*
X166615D01*
G01X174859Y469220D02*
X175713Y470074D01*
X186997D01*
X188457Y468614D01*
Y468481D01*
G01X165317Y465426D02*
Y461561D01*
G01X165360Y473157D02*
X166500Y474297D01*
Y475829D01*
X167597Y476926D01*
Y477799D01*
X168592Y478794D01*
X172354D01*
X172415Y478733D01*
G01X161455Y453385D02*
X161705D01*
X163154Y454834D01*
X168281D01*
X168407Y454960D01*
X172317D01*
X172529Y455172D01*
X173939D01*
X174151Y454960D01*
X186389D01*
X186736Y454613D01*
X190415D01*
X193581Y457779D01*
G01X177763Y486293D02*
X181007D01*
X181400Y485900D01*
G01X149799Y452376D02*
X152456D01*
X153463Y453383D01*
G01X157411Y469344D02*
Y470078D01*
X159186Y471853D01*
Y474690D01*
X157500Y476376D01*
Y476921D01*
G01X161423Y477094D02*
X163653Y479324D01*
Y489603D01*
X164711Y490661D01*
Y495322D01*
G01X157486Y461346D02*
Y461962D01*
X153915Y465533D01*
G01X153690Y469111D02*
Y469660D01*
X150029Y473321D01*
G01X208947Y443700D02*
X208896D01*
X206346Y441150D01*
X205881D01*
G01X196803Y444462D02*
Y444621D01*
X199315Y447133D01*
Y447233D01*
G01X201400Y434400D02*
X201559Y434241D01*
X205301D01*
X206917Y435857D01*
G01X180313Y446694D02*
X178375Y444756D01*
X175362D01*
X172820Y447298D01*
X163431D01*
X161423Y449306D01*
Y449430D01*
G01X161670Y418161D02*
X163571Y416260D01*
X177460D01*
X178200Y417000D01*
X191226D01*
X197326Y423100D01*
X214014D01*
X236807Y445893D01*
X238193D01*
X241300Y449000D01*
G01X176662Y418122D02*
X176762Y418222D01*
X190185D01*
X196663Y424700D01*
X213351D01*
X221800Y433149D01*
Y436500D01*
G01X173458Y457178D02*
X173564Y457284D01*
X180831D01*
X181234Y456881D01*
X187657D01*
X187689Y456913D01*
G01X178053Y474260D02*
X178353Y474560D01*
X182377D01*
G01X174601Y481467D02*
X175786Y482652D01*
Y486922D01*
X176175Y487311D01*
Y494951D01*
X170474Y500652D01*
G01X165319Y453134D02*
X166519D01*
X168153Y451500D01*
X174433D01*
X175216Y452283D01*
X179407D01*
G01X165353Y480812D02*
X168118Y483577D01*
Y483682D01*
G01X250400Y473300D02*
Y473200D01*
X247800Y470600D01*
X229563D01*
X216600Y457637D01*
Y456100D01*
X212300Y451800D01*
Y439300D01*
G01X157486Y433783D02*
X159585Y435882D01*
X163118D01*
X163655Y435345D01*
Y431945D01*
X164310Y431290D01*
X166116D01*
X167111Y430295D01*
Y428689D01*
X169200Y426600D01*
X175800D01*
X176900Y425500D01*
X184843D01*
X190621Y431278D01*
X206478D01*
X212300Y437100D01*
Y439300D01*
G01X165360Y421972D02*
X167510Y419822D01*
X189522D01*
X196000Y426300D01*
X212688D01*
X219600Y433212D01*
Y441300D01*
X226000Y447700D01*
G01X153646Y457393D02*
X155899Y459646D01*
X158191D01*
X158406Y459861D01*
X166022D01*
X167710Y461549D01*
X173738D01*
X173765Y461522D01*
G01X161294Y461561D02*
X159663Y463192D01*
Y465693D01*
G01X165363Y425783D02*
X170379Y420767D01*
X184636D01*
X191769Y427900D01*
X212025D01*
X218000Y433875D01*
Y443000D01*
X229050Y454050D01*
X232250D01*
X233900Y455700D01*
G01X157393Y457572D02*
X159248D01*
X160737Y459061D01*
X166074D01*
X166392Y458743D01*
X168824D01*
G01X233050Y474200D02*
X230900D01*
X214999Y458299D01*
Y456799D01*
X209000Y450800D01*
Y447500D01*
G01X181034Y427967D02*
Y428834D01*
X184000Y431800D01*
X189663D01*
X199581Y441718D01*
X203218D01*
X209000Y447500D01*
G01X177700Y427300D02*
Y428100D01*
X183000Y433400D01*
X189000D01*
X213043Y457443D01*
Y459443D01*
X223500Y469900D01*
G01X165355Y433382D02*
X166573Y434600D01*
X172879D01*
X174456Y433023D01*
X179623D01*
X181700Y435100D01*
X186237D01*
X194199Y443062D01*
Y445737D01*
X199700Y451238D01*
Y453805D01*
X205045Y459150D01*
X206400D01*
X208200Y460950D01*
Y462637D01*
X226863Y481300D01*
X228800D01*
G01X165355Y437582D02*
X165718D01*
X167300Y436000D01*
X173919D01*
X174719Y436800D01*
X185674D01*
X192599Y443725D01*
Y446400D01*
X198100Y451901D01*
Y454800D01*
X205400Y462100D01*
G01X233050Y486500D02*
X230750Y484200D01*
X227500D01*
X205400Y462100D01*
G01X165360Y445598D02*
X166752D01*
X168452Y443898D01*
X171250D01*
X172615Y442533D01*
G01X157411Y449556D02*
X158987D01*
X160561Y451130D01*
X162128D01*
X162252Y451006D01*
X166694D01*
X168134Y449566D01*
X186066D01*
X186200Y449700D01*
G01X169157Y445598D02*
X169600Y445155D01*
X173392D01*
X175711Y442836D01*
X180407D01*
X183681Y439562D01*
X184252D01*
G01X157508Y480990D02*
X157635Y481116D01*
G03X159425Y485439I-4323J4322D01*
G02X160060Y486972I2168J0D01*
G03X160486Y488387I-2140J1416D01*
G01Y489773D01*
G03X159681Y491718I-2752J0D01*
G02X159419Y492351I633J633D01*
G01Y492708D01*
G02X160180Y494545I2598J0D01*
G01X160644Y495009D01*
X160645D01*
X252582Y586947D01*
X253336Y587700D01*
G02X273404Y596013I20069J-20068D01*
G01X747523D01*
G02X749785Y595075I-1J-3200D01*
G01X755159Y589701D01*
G03X759261Y588003I4101J4103D01*
G01X769516D01*
G03X769521I2J3681D01*
G01X769961D01*
G02X771900Y587200I0J-2742D01*
G03X773264Y586635I1364J1364D01*
G01X781514D01*
G01X165288Y449306D02*
X165550D01*
X166362Y448494D01*
X181114D01*
X185408Y444200D01*
X187600D01*
G01X157486Y484968D02*
Y485372D01*
G02X158045Y486722I1909J0D01*
G01X158815Y487493D01*
G03X159186Y488387I-894J895D01*
G01Y489772D01*
G03X158761Y490798I-1451J0D01*
G02X158500Y491113I1544J1545D01*
G02X158119Y492351I1814J1236D01*
G01Y492709D01*
G02X159260Y495465I3899J0D01*
G01X252414Y588619D01*
G02X273403Y597313I20989J-20989D01*
G01X280480D01*
X280920Y597753D01*
X282120D01*
X282560Y597313D01*
X283760D01*
X284200Y597753D01*
X285400D01*
X285840Y597313D01*
X287040D01*
X287480Y597753D01*
X288680D01*
X289120Y597313D01*
X290320D01*
X290760Y597753D01*
X291960D01*
X292400Y597313D01*
X342400D01*
X342840Y597753D01*
X344040D01*
X344480Y597313D01*
X345680D01*
X346120Y597753D01*
X347320D01*
X347760Y597313D01*
X747523D01*
G02X750705Y595995I0J-4500D01*
G01X756079Y590621D01*
G03X759261Y589303I3182J3182D01*
G01X769517D01*
G03X771200Y590000I0J2380D01*
G02X772588Y590575I1388J-1388D01*
G01X781514D01*
G01X153601Y480894D02*
X154054Y481346D01*
G03X155388Y484568I-3222J3221D01*
G01Y493829D01*
G02X159000Y502549I12332J0D01*
G01X252892Y596441D01*
G02X267242Y602385I14350J-14350D01*
G01X781514D01*
G01X153586Y485118D02*
G03X153853Y485464I-1212J1212D01*
G03X154088Y486330I-1479J866D01*
G01Y493830D01*
G02X158080Y503468I13632J-1D01*
G01Y503469D01*
X251972Y597361D01*
G02X267241Y603685I15269J-15271D01*
G01X271041D01*
X271441Y604085D01*
X272441D01*
X272841Y603685D01*
X273841D01*
X274241Y604085D01*
X275241D01*
X275641Y603685D01*
X276641D01*
X277041Y604085D01*
X278041D01*
X278441Y603685D01*
X279441D01*
X279841Y604085D01*
X280841D01*
X281241Y603685D01*
X282241D01*
X282641Y604085D01*
X283641D01*
X284041Y603685D01*
X768722D01*
G03X771902Y605002I0J4498D01*
G02X775084Y606320I3182J-3182D01*
G01X781514D01*
G01X149620Y485149D02*
Y485796D01*
G02X150041Y486812I1437J0D01*
G01X150878Y487649D01*
G03X151312Y488697I-1048J1048D01*
G01Y499821D01*
X151313D01*
G02X156886Y513278I19028J2D01*
G01X157024Y513415D01*
X246800Y603191D01*
G02X288226Y620350I41425J-41425D01*
G01X289226D01*
X289626Y620750D01*
X290626D01*
X291026Y620350D01*
X292026D01*
X292426Y620750D01*
X293426D01*
X293826Y620350D01*
X294826D01*
X295226Y620750D01*
X296226D01*
X296626Y620350D01*
X297626D01*
X298026Y620750D01*
X299026D01*
X299426Y620350D01*
X300426D01*
X300826Y620750D01*
X301826D01*
X302226Y620350D01*
X303226D01*
X303626Y620750D01*
X304626D01*
X305026Y620350D01*
X769634D01*
G03X771710Y621210I0J2936D01*
G02X773786Y622070I2076J-2076D01*
G01X781514D01*
G01X161423Y433783D02*
Y430477D01*
X164417Y427483D01*
X166485D01*
X171768Y422200D01*
X177192D01*
X179392Y424400D01*
X186006D01*
X191106Y429500D01*
X211362D01*
X216400Y434538D01*
Y443663D01*
X229537Y456800D01*
X231482D01*
X239182Y464500D01*
X243300D01*
G01X174475Y488016D02*
Y488689D01*
X174468Y488696D01*
Y492763D01*
X172992Y494239D01*
G01X178084Y493198D02*
X177763Y492877D01*
Y486293D01*
G01X155786Y814140D02*
G03X156469Y814423I0J966D01*
G01X159589Y817543D01*
G01X154301Y832781D02*
X154815Y832266D01*
G03X155700Y831900I884J885D01*
G01X158278D01*
G03X159688Y832484I0J1994D01*
G01X154190Y837095D02*
G02X158726Y838974I4536J-4536D01*
G01X159431D01*
G01X154301Y828981D02*
X155510Y830190D01*
G02X156500Y830600I990J-990D01*
G01X157913D01*
G02X158611Y830311I0J-987D01*
G01X159688Y829234D01*
G01X155786Y817740D02*
X156497D01*
G03X157851Y818301I0J1915D01*
G01X158844Y819294D01*
G03X159137Y820001I-706J707D01*
G01Y820712D01*
G01X155038Y853750D02*
G02X156275Y853237I-1J-1750D01*
G01X157280Y852233D01*
G03X159060Y851564I1779J2032D01*
G01X159688D01*
G01X153990Y840895D02*
X157216D01*
G03X159038Y841649I1J2576D01*
G01X159560Y842172D01*
G01X155111Y850210D02*
X156949D01*
G02X158014Y849769I0J-1506D01*
G01X159426Y848357D01*
G01X301437Y426833D02*
X301078D01*
X289353Y415108D01*
Y414756D01*
X279629Y405032D01*
G01X304200Y432600D02*
X303248Y431648D01*
X303151D01*
X266336Y394833D01*
X257015D01*
G01X297238Y429641D02*
X267190Y399593D01*
X260600D01*
X259093Y401100D01*
X251600D01*
X249300Y398800D01*
G01X285565Y438912D02*
Y434083D01*
X264034Y412552D01*
X255152D01*
X251100Y408500D01*
G01X273554Y386722D02*
X273604D01*
X306350Y419468D01*
Y427950D01*
X355247Y476847D01*
X356380D01*
G01X242100Y489000D02*
X244600Y486500D01*
Y485200D01*
G01X279120Y440440D02*
X278122D01*
X267673Y429991D01*
G01X276761Y443421D02*
X258599Y425259D01*
X255955D01*
X251737Y421041D01*
X241537D01*
X237576Y417080D01*
G01X277575Y449398D02*
X277339Y449162D01*
X277304D01*
X256601Y428459D01*
X253741D01*
X253615Y428333D01*
G01X270714Y458323D02*
Y457714D01*
X245000Y432000D01*
G01X263719Y455536D02*
X261536D01*
X258100Y452100D01*
G01X220768Y418393D02*
Y421014D01*
X234854Y435100D01*
X239230D01*
X241565Y437435D01*
G01X259779Y456823D02*
X258775D01*
X255076Y453124D01*
Y450946D01*
X241565Y437435D01*
G01X260322Y462288D02*
X258934D01*
X255146Y458500D01*
X253500D01*
G01X256852Y465331D02*
X256605D01*
X247874Y456600D01*
Y454774D01*
X242100Y449000D01*
X241300D01*
G01X258221Y469246D02*
X247275Y458300D01*
X243609D01*
X234909Y449600D01*
X231500D01*
X221800Y439900D01*
Y436500D01*
G01X235069Y464940D02*
X237355Y467226D01*
X237980D01*
G01X271342Y440630D02*
X271035D01*
X257264Y426859D01*
X255292D01*
X252033Y423600D01*
X240400D01*
G01X264775Y459236D02*
X264162Y458623D01*
X258312D01*
X246842Y447153D01*
X244779D01*
X240319Y442693D01*
X238847D01*
X224015Y427861D01*
Y427633D01*
G01X279789Y432846D02*
X267479Y420536D01*
G01X260481Y473769D02*
X260198D01*
X255014Y468585D01*
Y468302D01*
X246712Y460000D01*
X243046D01*
X234646Y451600D01*
X229900D01*
X226000Y447700D01*
G01X253214Y469048D02*
X246066Y461900D01*
X239054D01*
X234977Y457823D01*
Y456777D01*
X233900Y455700D01*
G01X233050Y478300D02*
X229500D01*
X223500Y472300D01*
Y469900D01*
G01X233050Y482400D02*
X229900D01*
X228800Y481300D01*
G01X249845Y469508D02*
X248980Y468643D01*
Y467919D01*
X245561Y464500D01*
X243300D01*
G01X236550Y482400D02*
X236663D01*
X239100Y484837D01*
Y488937D01*
X246013Y495850D01*
X259950D01*
X274200Y510100D01*
Y531500D01*
X287800Y545100D01*
X442963D01*
X462763Y564900D01*
X580800D01*
X600300Y584400D01*
X680300D01*
G01X236550Y478300D02*
X280369D01*
X306969Y504900D01*
X453500D01*
X460750Y497650D01*
X485050D01*
X489000Y493700D01*
G01X236550Y474200D02*
X239050Y476700D01*
X281032D01*
X307632Y503300D01*
X452837D01*
X460421Y495716D01*
X483684D01*
X493050Y486350D01*
G01X229300Y442500D02*
X226818Y440018D01*
Y439263D01*
G01X283657Y532832D02*
X284157Y533332D01*
X467668D01*
X498794Y502206D01*
Y493300D01*
G01X280259Y532714D02*
X280286D01*
X282804Y535232D01*
X468456D01*
X500894Y502794D01*
Y499600D01*
G01X236550Y486500D02*
X236318Y486732D01*
Y494518D01*
X239250Y497450D01*
X259287D01*
X272600Y510763D01*
Y532200D01*
X287100Y546700D01*
X442300D01*
X462100Y566500D01*
X580137D01*
X600337Y586700D01*
X626700D01*
G01X281183Y592936D02*
X726646D01*
X736176Y583406D01*
G01X300059Y422844D02*
X291453Y414238D01*
G01X290615Y432406D02*
X300603D01*
G01X304550Y424222D02*
Y422368D01*
X299330Y417148D01*
G01X356380Y476847D02*
X367177Y487644D01*
X437056D01*
X441000Y483700D01*
Y479370D01*
X431099Y469469D01*
G01X427599D02*
X430900Y466168D01*
Y462018D01*
X428968Y460086D01*
Y458442D01*
G01X427599Y469469D02*
Y474101D01*
X426700Y475000D01*
G01X420082Y475470D02*
X426230D01*
X426700Y475000D01*
G01X420575Y467336D02*
X421784Y466127D01*
Y463067D01*
G01X420088Y471346D02*
Y467823D01*
X420575Y467336D01*
G01X420088Y471346D02*
X423300D01*
X423746Y470900D01*
G01X504500Y479500D02*
X503200D01*
X489000Y493700D01*
G01X501700Y477200D02*
Y477700D01*
X493050Y486350D01*
G01X498994Y488322D02*
X498794Y488522D01*
Y493300D01*
G01X501802Y490240D02*
X500894Y491148D01*
Y499600D01*
G01X663300Y522050D02*
X650862D01*
X634700Y538212D01*
Y544300D01*
G01X632600Y555200D02*
X633985Y553815D01*
Y545015D01*
X634700Y544300D01*
G01X640900Y546800D02*
X641308D01*
X643833Y549325D01*
G01X639200Y540600D02*
Y536400D01*
X651604Y523996D01*
X661146D01*
X663300Y526150D01*
G01X639200Y540600D02*
Y542770D01*
X635885Y546085D01*
Y554785D01*
X636200Y555100D01*
G01X639900Y554500D02*
Y550800D01*
X640100Y550600D01*
G01D02*
X641200D01*
X642650Y552050D01*
X648200D01*
G01X643100Y589900D02*
X639900Y586700D01*
X626700D01*
G01X689111Y438262D02*
X688409Y438964D01*
Y442578D01*
G01X693874Y448220D02*
Y446699D01*
X691337Y444162D01*
X689993D01*
X688409Y442578D01*
G01X693509Y438351D02*
Y442556D01*
X693409Y442656D01*
G01X695842Y448220D02*
Y445089D01*
X693409Y442656D01*
G01X698475Y489824D02*
X698356D01*
X693874Y485342D01*
Y483820D01*
G01X702508Y434954D02*
Y431608D01*
X702400Y431500D01*
G01X689996Y489797D02*
X689101D01*
X685258Y485954D01*
Y480260D01*
X685718Y479800D01*
X687858D01*
G01X702508Y438454D02*
X703400Y439346D01*
Y442200D01*
G01X701858Y450272D02*
Y443742D01*
X703400Y442200D01*
G01X698367Y434952D02*
Y431667D01*
X698300Y431600D01*
G01X698367Y438452D02*
X698404Y438489D01*
Y442423D01*
G01X697811Y448220D02*
X699638D01*
X699958Y447900D01*
Y443977D01*
X698404Y442423D01*
G01X702000Y485700D02*
X700120Y483820D01*
X697811D01*
G01X702648Y489787D02*
Y486348D01*
X702000Y485700D01*
G01X701858Y481768D02*
X704445Y484355D01*
Y487046D01*
X707296Y489897D01*
G01X688615Y485133D02*
X687858Y484376D01*
Y481768D01*
G01X694196Y489897D02*
X691573Y487274D01*
X690756D01*
X688615Y485133D01*
G01X685815Y489828D02*
X684620Y488633D01*
X684615D01*
X683658Y487676D01*
Y479474D01*
X685301Y477831D01*
X687858D01*
G01X707109Y438473D02*
X709315Y440679D01*
Y443333D01*
G01D02*
Y445000D01*
X705659Y448656D01*
Y451041D01*
X704460Y452240D01*
X701858D01*
G01X675415Y437533D02*
X679988D01*
X680738Y438283D01*
G01D02*
Y443838D01*
X684300Y447400D01*
X686455D01*
X687858Y448803D01*
Y450272D01*
G01X684869Y438261D02*
X683409Y439721D01*
Y442604D01*
G01X691905Y448220D02*
X691020D01*
X688400Y445600D01*
X686405D01*
X683409Y442604D01*
G01X701858Y477831D02*
X704231D01*
X707000Y480600D01*
X708300D01*
G01X712195Y480900D02*
X711895Y480600D01*
X708300D01*
G01X712195Y485000D02*
X711395Y485800D01*
X707900D01*
G01X701858Y479800D02*
X704200D01*
X704700Y480300D01*
Y482200D01*
X706045Y483545D01*
Y483945D01*
X707900Y485800D01*
G01X671145Y454348D02*
Y452831D01*
G03X671800Y451250I2236J0D01*
G03X673900I1050J1050D01*
G03X674200Y451974I-724J724D01*
G01Y453939D01*
G02X674950Y455750I2561J0D01*
G01X675300Y456100D01*
G02X679431Y457811I4131J-4131D01*
G01X684363D01*
G03X684768Y457978I1J572D01*
G01X684818Y458028D01*
G02X685101Y458146I284J-282D01*
G01X687858D01*
G01X717993Y451389D02*
G02X717593Y452355I966J966D01*
G01Y454740D01*
G03X716707Y456882I-3033J0D01*
G01X716591Y456998D01*
G03X714725Y457772I-1865J-1859D01*
G01X704792D01*
G02X704341Y457959I0J637D01*
G03X703890Y458146I-451J-450D01*
G01X701858D01*
G01X658195Y464248D02*
Y467631D01*
G02X658488Y468338I1000J0D01*
G01X659680Y469530D01*
G02X660387Y469823I707J-706D01*
G01X683500D01*
G02X684188Y469538I0J-973D01*
G01X685207Y468519D01*
G03X686487Y467989I1280J1280D01*
G01X687858D01*
G01X731751Y464398D02*
Y466564D01*
G03X731302Y467648I-1533J0D01*
G01X729915Y469035D01*
G03X728501Y469621I-1414J-1413D01*
G01X707756D01*
G03X706711Y469188I0J-1478D01*
G01X706511Y468988D01*
G02X704099Y467989I-2412J2412D01*
G01X701858D01*
G01X687858Y469957D02*
X686315D01*
G02X685108Y470457I0J1707D01*
G03X683500Y471123I-1608J-1608D01*
G01X660387D01*
G03X658760Y470450I-1J-2300D01*
G01X658230Y469920D01*
G02X657095Y469450I-1135J1135D01*
G01X654915D01*
G02X653351Y470098I0J2212D01*
G01X735259Y469898D02*
X734942Y469582D01*
G02X733688Y469062I-1255J1254D01*
G02X733450Y469050I-236J2308D01*
G01X732299D01*
G02X732130Y469060I-5J1349D01*
G02X731345Y469445I170J1339D01*
G01X730835Y469955D01*
G03X728501Y470921I-2333J-2334D01*
G01X707755D01*
G03X705791Y470108I0J-2779D01*
G01X705790Y470107D01*
G02X705428Y469957I-362J362D01*
G01X701858D01*
G01X721445Y455789D02*
X721692D01*
G03X723650Y456600I0J2769D01*
G03X723900Y457204I-605J604D01*
G01Y458686D01*
G03X723607Y459393I-999J0D01*
G01X722779Y460221D01*
G03X722072Y460514I-707J-706D01*
G01X704846D01*
G03X704315Y460294I0J-751D01*
G02X703637Y460114I-678J1186D01*
G01X701858D01*
G01X726589Y460909D02*
X724406D01*
G02X723625Y461212I0J1158D01*
G03X722072Y461814I-1551J-1698D01*
G01X704700D01*
G02X704205Y462019I0J700D01*
G03X703868Y462083I-337J-854D01*
G01X701858D01*
G01Y473894D02*
X725901D01*
G03X728023Y474773I0J3001D01*
G01X730668Y477418D01*
G02X732790Y478297I2122J-2122D01*
G01X743520D01*
G01X738745Y472789D02*
G03X739588Y473138I0J1193D01*
G01X740148Y473698D01*
G03X740822Y475325I-1627J1627D01*
G01Y475770D01*
G03X740462Y476638I-1226J0D01*
G03X739595Y476997I-867J-867D01*
G01X732790D01*
G03X731588Y476498I1J-1700D01*
G01X728943Y473853D01*
G02X725901Y472594I-3041J3042D01*
G01X705184D01*
G03X704363Y472254I0J-1161D01*
G02X703571Y471926I-792J792D01*
G01X701858D01*
G01X667745Y456089D02*
Y457617D01*
G02X668331Y459031I1999J0D01*
G01X669137Y459837D01*
G02X670551Y460423I1414J-1413D01*
G01X684805D01*
G02X685261Y460234I0J-645D01*
G03X685749Y460114I489J935D01*
G01X687858D01*
G01X662604Y463284D02*
X665393Y460495D01*
G03X667955I1281J1281D01*
G01X668217Y460757D01*
G02X670551Y461723I2333J-2334D01*
G01X684718D01*
G03X685242Y461940I0J741D01*
G02X685818Y462083I575J-1086D01*
G01X687858D01*
G01X650837Y472421D02*
Y473533D01*
G02X651415Y474928I1973J0D01*
G02X652829Y475514I1414J-1413D01*
G01X663858D01*
G02X665272Y474928I0J-1999D01*
G01X667020Y473180D01*
G03X668434Y472594I1414J1413D01*
G01X684703D01*
G02X685556Y472240I-1J-1207D01*
G01X685593Y472204D01*
G03X686264Y471926I671J671D01*
G01X687858D01*
G01Y473894D02*
X668434D01*
G02X667940Y474100I1J698D01*
G01X666192Y475848D01*
G03X663858Y476814I-2333J-2334D01*
G01X651917D01*
G02X646251Y479161I0J8013D01*
G01X675745Y448189D02*
G02X675500Y448780I590J591D01*
G01Y453940D01*
X675501Y453939D01*
G02X675870Y454830I1260J0D01*
G01X676220Y455180D01*
G02X679431Y456511I3212J-3210D01*
G01X684353D01*
G02X684756Y456344I0J-570D01*
G03X685159Y456177I403J403D01*
G01X687858D01*
G01X713845Y447289D02*
X714750D01*
G03X715841Y447741I0J1543D01*
G03X716293Y448832I-1091J1091D01*
G01Y454739D01*
G03X715785Y455964I-1732J-1D01*
G01X715669Y456081D01*
G03X714725Y456472I-943J-942D01*
G01X704566D01*
G03X704283Y456354I1J-400D01*
G01X704253Y456324D01*
G02X703896Y456177I-356J357D01*
G01X701858D01*
G01X689945Y518741D02*
Y525100D01*
X688695Y526350D01*
X682750D01*
X680800Y524400D01*
G01X663300Y522050D02*
X663738D01*
X668300Y526612D01*
Y529712D01*
X669209Y530621D01*
X673239D01*
X676760Y527100D01*
X677900D01*
X680600Y524400D01*
X680800D01*
G01X657270Y540455D02*
Y548930D01*
X656592Y549608D01*
X649758D01*
X648200Y548050D01*
G01X643833Y549325D02*
X646925D01*
X648200Y548050D01*
G01X689945Y535041D02*
Y530195D01*
X688000Y528250D01*
X681550D01*
X680800Y529000D01*
G01X663300Y526150D02*
X665150D01*
X666400Y527400D01*
Y530500D01*
X668421Y532521D01*
X674027D01*
X677548Y529000D01*
X680800D01*
G01X657270Y556755D02*
Y552678D01*
X656100Y551508D01*
X648742D01*
X648200Y552050D01*
G01X695065Y518741D02*
Y513115D01*
X693350Y511400D01*
G01D02*
X689400D01*
X689200Y511600D01*
G01X662390Y540455D02*
X664145D01*
X666985Y537615D01*
X668743D01*
G01X673100Y535400D02*
X670958D01*
X668743Y537615D01*
G01X714662Y537033D02*
Y544133D01*
X712795Y546000D01*
X710212D01*
X709162Y547050D01*
X705600D01*
G01D02*
X705131Y546581D01*
X702000D01*
G01X714662Y553333D02*
Y548588D01*
X713974Y547900D01*
X711000D01*
X707750Y551150D01*
X705600D01*
G01D02*
X702950D01*
X702400Y550600D01*
G01X712102Y553333D02*
X709967D01*
X708900Y554400D01*
Y555100D01*
X706695Y557305D01*
Y559800D01*
G01X659830Y556755D02*
Y552351D01*
X660500Y551681D01*
X667800D01*
X668699Y552580D01*
G01D02*
X675280D01*
X680700Y558000D01*
G01X668705Y548594D02*
X670186Y550075D01*
X676414D01*
X684139Y557800D01*
X688600D01*
G01X668705Y548594D02*
X667518Y549781D01*
X660597D01*
X659830Y549014D01*
Y540455D01*
G01X707296Y489897D02*
X711197D01*
X711500Y490200D01*
G01X712850Y529600D02*
X711550Y528300D01*
X706304D01*
X705927Y528677D01*
G01X701500Y529000D02*
X705604D01*
X705927Y528677D01*
G01X692505Y535041D02*
Y528747D01*
X693852Y527400D01*
X699900D01*
X701500Y529000D01*
G01X705928Y524695D02*
X707633Y526400D01*
X711950D01*
X712850Y525500D01*
G01X701500Y524400D02*
X700400Y525500D01*
X693800D01*
X692505Y524205D01*
Y518741D01*
G01X705928Y524695D02*
X705633Y524400D01*
X701500D01*
G01X682015Y493633D02*
Y493628D01*
X685815Y489828D01*
G01X686350Y545500D02*
Y543745D01*
X687000Y543095D01*
Y537785D01*
X687385Y537400D01*
Y535041D01*
G01X686350Y545500D02*
Y549350D01*
X685800Y549900D01*
G01X710776Y560695D02*
X707590D01*
X706695Y559800D01*
G01X697600Y560000D02*
X697500Y559900D01*
X682600D01*
X680700Y558000D01*
G01X688600Y557800D02*
X698088D01*
X700488Y560200D01*
X701400D01*
G01X654710Y556755D02*
Y560590D01*
X653317Y561983D01*
Y563931D01*
G01D02*
X652815Y564433D01*
X649633D01*
X649500Y564300D01*
G01X727700Y584400D02*
X680300D01*
G01X724305Y770450D02*
Y768974D01*
X718135Y762804D01*
X704215D01*
G01D02*
X697257D01*
G01X697279Y766898D02*
X697606Y766571D01*
X712215D01*
G01X693757Y762804D02*
X691210D01*
X668276Y739870D01*
X667982D01*
G01X681402Y757754D02*
X684515Y760867D01*
G01X693779Y766898D02*
X691584Y764703D01*
X688351D01*
X684515Y760867D01*
G01X693863Y775149D02*
X678989D01*
X663575Y759735D01*
Y742289D01*
G01X727477Y775212D02*
X725748Y776941D01*
X720691D01*
X714763Y771013D01*
X703515D01*
G01D02*
X697320D01*
G01X697363Y775149D02*
X711815D01*
G01X697384Y779285D02*
X703415D01*
G01X730028Y782297D02*
X724922D01*
X724425Y781800D01*
X721024D01*
X718509Y779285D01*
X703415D01*
G01X697405Y783400D02*
X713015D01*
G01X729988Y787114D02*
X729932Y787170D01*
X724493D01*
X724064Y787599D01*
X704215D01*
G01D02*
X697448D01*
G01X697743Y791967D02*
X715515D01*
G01X729486Y791416D02*
X728161Y792740D01*
X724661D01*
X717945Y799456D01*
X704215D01*
G01X697954Y796145D02*
X701265Y799456D01*
X704215D01*
G01X698080Y800492D02*
X699605Y802017D01*
X713915D01*
G01X697250Y829925D02*
X713715D01*
G01X697229Y834000D02*
X704015D01*
G01X721704Y829981D02*
X717685Y834000D01*
X704015D01*
G01X693820Y771013D02*
X693058D01*
X690522Y773549D01*
X680727D01*
X680480Y773302D01*
G01X678755Y784815D02*
Y783060D01*
X680706Y781109D01*
G01X693884Y779285D02*
X682530D01*
X680706Y781109D01*
G01X693905Y783400D02*
X687848D01*
G01X676727Y790555D02*
X676791D01*
X683946Y783400D01*
X687848D01*
G01X693948Y787599D02*
X687887D01*
X679630Y795856D01*
G01X680239Y802378D02*
Y799903D01*
X686672Y793470D01*
G01X694243Y791967D02*
X688175D01*
X686672Y793470D01*
G01X682693Y806283D02*
X684072Y804904D01*
Y803530D01*
X685389Y802213D01*
G01X694454Y796145D02*
X691457D01*
X685389Y802213D01*
G01X694580Y800492D02*
X684732Y810340D01*
Y810518D01*
G01X693750Y829925D02*
X680279D01*
X668316Y817962D01*
Y787682D01*
X669886Y786112D01*
G01X693729Y834000D02*
X687110D01*
X686308Y834802D01*
G01X693770Y838158D02*
X658031D01*
X646342Y826469D01*
G01X733066Y836450D02*
X724243Y827627D01*
Y825717D01*
X723189Y824663D01*
X705215D01*
G01X697306Y825792D02*
X698435Y824663D01*
X705215D01*
G01X693806Y825792D02*
X691820D01*
X690211Y827401D01*
G01X689760Y854661D02*
X689688D01*
X687260Y852233D01*
X683715D01*
G01X693897Y854741D02*
X689840D01*
X689760Y854661D01*
G01X710727Y862002D02*
X719396D01*
X726013Y855385D01*
G01X686260Y854661D02*
X678629D01*
X678351Y854383D01*
G01X713015Y838158D02*
X697270D01*
G01X697318Y842302D02*
X703515D01*
G01X723801Y834857D02*
X723777D01*
X716332Y842302D01*
X703515D01*
G01X726332Y837128D02*
X723981D01*
X714714Y846395D01*
X711415D01*
G01D02*
X697337D01*
G01X697366Y850609D02*
X703415D01*
G01X724093Y840187D02*
X713671Y850609D01*
X703415D01*
G01X693818Y842302D02*
X679768D01*
X679332Y841866D01*
G01X693837Y846395D02*
X682569D01*
X681156Y844982D01*
G01X693866Y850609D02*
X691618Y848361D01*
X681542D01*
G01X697397Y854741D02*
X714312D01*
X716539Y852514D01*
G01X762900Y387400D02*
X767300Y383000D01*
X773600D01*
X774690Y381910D01*
X781514D01*
G01X735191Y453967D02*
G02X735500Y454095I309J-309D01*
G01X770072D01*
G02X771665Y453435I0J-2252D01*
G03X773258Y452775I1593J1592D01*
G01X781514D01*
G01X735231Y457167D02*
X735685Y456713D01*
G03X738867Y455395I3182J3182D01*
G01X770162D01*
G03X771755Y456055I0J2252D01*
G02X773348Y456715I1593J-1592D01*
G01X781514D01*
G01X746845Y476389D02*
X747410Y475823D01*
G03X748776Y475258I1365J1366D01*
G01X754497D01*
G02X757679Y473940I0J-4500D01*
G01X759159Y472460D01*
G03X762341Y471142I3182J3182D01*
G01X770610D01*
G03X772201Y471801I0J2250D01*
G02X773792Y472460I1591J-1591D01*
G01X781514D01*
G01X746845Y473189D02*
G02X748702Y473958I1857J-1857D01*
G01X754497D01*
G02X756759Y473020I-1J-3200D01*
G01X758239Y471540D01*
G03X762341Y469842I4101J4103D01*
G01X770792D01*
G02X772100Y469300I0J-1849D01*
G01X772216Y469183D01*
G03X773806Y468525I1589J1590D01*
G01X781514D01*
G01X716350Y525500D02*
X719300D01*
X719800Y525000D01*
G01X716350Y529600D02*
X718922D01*
X719866Y528656D01*
G01X781514Y527580D02*
X757033D01*
X754457Y530156D01*
G01X752874Y534854D02*
Y531739D01*
X754457Y530156D01*
G01X781514Y519705D02*
X761917D01*
X760684Y518472D01*
X747015D01*
G01X737297Y517903D02*
X737866Y518472D01*
X747015D01*
G01X781514Y523645D02*
X769945D01*
X768700Y522400D01*
X765548D01*
X763715Y524233D01*
X759115D01*
G01X756523Y520272D02*
Y521641D01*
X759115Y524233D01*
G01X781514Y531515D02*
X765533D01*
X761015Y536033D01*
G01X749493Y535216D02*
X751072Y536795D01*
X760253D01*
X761015Y536033D01*
G01X726040Y547146D02*
X726758Y546428D01*
X732240D01*
X734600Y548788D01*
Y552100D01*
X742400Y559900D01*
G01X726040Y547146D02*
X725327Y546433D01*
X718000D01*
X717222Y547211D01*
Y553333D01*
G01X739385Y553915D02*
X736500Y551030D01*
Y548000D01*
X733028Y544528D01*
X727370D01*
X726045Y543203D01*
G01X749450Y559200D02*
X748350Y560300D01*
X745770D01*
X739385Y553915D01*
G01X717222Y537033D02*
Y544133D01*
X717622Y544533D01*
X724715D01*
X726045Y543203D01*
G01X728300Y531200D02*
Y534250D01*
X726850Y535700D01*
G01D02*
X725650Y536900D01*
X719915D01*
X719782Y537033D01*
G01X726800Y527400D02*
X726200Y528000D01*
X724927D01*
X724527Y528400D01*
X723500D01*
X719612Y532288D01*
X715090D01*
X712850Y530048D01*
Y529600D01*
G01X749450Y550600D02*
X746900D01*
X746000Y549700D01*
G01X723538Y526440D02*
Y525038D01*
X720800Y522300D01*
X714200D01*
X712850Y523650D01*
Y525500D01*
G01X742607Y549481D02*
Y549607D01*
X747700Y554700D01*
X749450D01*
G01X752100Y506500D02*
X753898D01*
X756433Y503965D01*
G01X781514Y503960D02*
X756438D01*
X756433Y503965D01*
G01X781514Y511830D02*
X764206D01*
X763276Y510900D01*
X761100D01*
X760267Y511733D01*
X754615D01*
G01X749500Y508800D02*
X752433Y511733D01*
X754615D01*
G01X781514Y500020D02*
X765502D01*
X764915Y499433D01*
X753867D01*
X748400Y504900D01*
X746300D01*
G01X742000Y505000D02*
X742100Y504900D01*
X746300D01*
G01X762275Y512870D02*
X761355Y513790D01*
Y516454D01*
G01X781514Y515770D02*
X771815D01*
X770852Y516733D01*
X762415D01*
X762136Y516454D01*
X761355D01*
G01X756400Y508100D02*
X756600Y508300D01*
X761900D01*
G01X781514Y507895D02*
X762305D01*
X761900Y508300D01*
G01X763000Y490800D02*
X767800Y495600D01*
X770400D01*
X770885Y496085D01*
X781514D01*
G01X752950Y554700D02*
X756900D01*
G01X781514Y555140D02*
X771300D01*
X770860Y554700D01*
X756900D01*
G01X781514Y551200D02*
X770200D01*
X769600Y551800D01*
X761000D01*
G01X752950Y550600D02*
X754150Y551800D01*
X761000D01*
G01X749450Y563300D02*
X748350Y562200D01*
X744700D01*
X742400Y559900D01*
G01X737400Y576200D02*
X736176Y577424D01*
Y583406D01*
G01X781514Y559075D02*
X772425D01*
X771600Y559900D01*
X764712D01*
X764112Y560500D01*
X761400D01*
G01X752950Y559200D02*
X754250Y560500D01*
X761400D01*
G01X752950Y563300D02*
X756900D01*
G01X781514Y563015D02*
X772315D01*
X771100Y561800D01*
X765500D01*
X764000Y563300D01*
X756900D01*
G01X757600Y639700D02*
X762700D01*
X768690Y645690D01*
X781514D01*
G01X723678Y774016D02*
X716233Y766571D01*
X712215D01*
G01X781514Y740179D02*
X774721D01*
X773400Y741500D01*
X756436D01*
X755115Y740179D01*
G01D02*
X746669D01*
G01X781514Y744114D02*
X743653D01*
G01X741453Y748054D02*
X781514D01*
G01X738850Y751989D02*
X781514D01*
G01Y755929D02*
X734450D01*
G01X730967Y759864D02*
X744615D01*
G01D02*
X781514D01*
G01X742663Y788885D02*
Y782255D01*
X761119Y763799D01*
X781514D01*
G01X724733Y779559D02*
X721046D01*
X716636Y775149D01*
X711815D01*
G01X724859Y784497D02*
X723762Y783400D01*
X713015D01*
G01X739510Y795264D02*
X744463Y790311D01*
Y784241D01*
X760965Y767739D01*
X781514D01*
G01X725239Y788970D02*
X722242Y791967D01*
X715515D01*
G01X745230Y793211D02*
X746063Y792378D01*
Y784904D01*
X759293Y771674D01*
X781514D01*
G01X742370Y799077D02*
Y798617D01*
X747663Y793324D01*
Y785567D01*
X757616Y775614D01*
X781514D01*
G01X725407Y794540D02*
X717930Y802017D01*
X713915D01*
G01X747659Y796960D02*
X749263Y795356D01*
Y789147D01*
X760510Y777900D01*
X772900D01*
X774549Y779549D01*
X781514D01*
G01X744790Y802781D02*
X754571Y793000D01*
X771100D01*
X772741Y791359D01*
X781514D01*
G01X749593Y803991D02*
X758285Y795299D01*
X781514D01*
G01X747556Y808994D02*
X757316Y799234D01*
X781514D01*
G01X749629Y812608D02*
X759068Y803169D01*
X781514D01*
G01X722443Y826463D02*
X718981Y829925D01*
X713715D01*
G01X724858Y831254D02*
X717954Y838158D01*
X713015D01*
G01X744700Y828200D02*
Y823063D01*
X758763Y809000D01*
X770700D01*
X772744Y811044D01*
X781514D01*
G01X741432Y850566D02*
X744700Y847298D01*
Y828200D01*
G01X781514Y807109D02*
X772509D01*
X770169Y804769D01*
X760731D01*
X742336Y823164D01*
Y838933D01*
G01X721243Y850725D02*
X721244D01*
X725522Y846447D01*
X731615D01*
G01D02*
X737912D01*
G01X737932Y850566D02*
X736298Y852200D01*
X729198D01*
X726013Y855385D01*
G01X716539Y852514D02*
X726776Y842277D01*
G01X738050Y859500D02*
X738213Y859200D01*
Y855068D01*
G01D02*
X734692D01*
X733796Y854172D01*
G01X741412Y846447D02*
X742336Y845523D01*
Y838933D01*
G54D18*
X76107Y131131D03*
Y138611D03*
X83977Y134871D03*
G54D36*
X77963Y273483D03*
Y270923D03*
Y268363D03*
Y242773D03*
Y245333D03*
Y247888D03*
Y250448D03*
Y253008D03*
Y255568D03*
Y258128D03*
Y260683D03*
Y263243D03*
Y265803D03*
Y291393D03*
Y288833D03*
Y286278D03*
Y283718D03*
Y281158D03*
Y278598D03*
Y276038D03*
X161963Y242773D03*
Y245333D03*
Y247888D03*
Y250448D03*
Y253008D03*
Y255568D03*
Y258128D03*
Y260683D03*
Y263243D03*
Y265803D03*
Y273483D03*
Y270923D03*
Y268363D03*
Y291393D03*
Y288833D03*
Y286278D03*
Y283718D03*
Y281158D03*
Y278598D03*
Y276038D03*
G54D27*
X50244Y180974D03*
Y191974D03*
X44879Y511272D03*
Y522272D03*
G54D45*
X57377Y500748D03*
G54D54*
X286982Y828335D03*
X276982D03*
X286982Y818335D03*
X276982D03*
X356982Y828335D03*
X346982D03*
X336982D03*
X326982D03*
X316982D03*
X306982D03*
X296982D03*
X356982Y818335D03*
X346982D03*
X336982D03*
X326982D03*
X316982D03*
X306982D03*
X296982D03*
X366982Y828335D03*
Y818335D03*
G54D63*
X779564Y330730D03*
Y740179D03*
G54D73*
G01X-755164Y-252763D02*
Y-235263D01*
G01X-746868D02*
X-755164Y-246055D01*
G01X-745558Y-252763D02*
X-751453Y-241097D01*
G01X-737883Y-252763D02*
Y-235263D01*
X-727839Y-252763D01*
Y-235263D01*
G01X-715361Y-252763D02*
X-717108Y-252471D01*
X-718636Y-251305D01*
X-719946Y-249555D01*
X-720820Y-247513D01*
X-721256Y-245180D01*
Y-242846D01*
X-720820Y-240513D01*
X-719946Y-238471D01*
X-718636Y-236722D01*
X-717108Y-235555D01*
X-715361Y-235263D01*
X-713615Y-235555D01*
X-712086Y-236722D01*
X-710776Y-238471D01*
X-709902Y-240513D01*
X-709466Y-242846D01*
Y-245180D01*
X-709902Y-247513D01*
X-710776Y-249555D01*
X-712086Y-251305D01*
X-713615Y-252471D01*
X-715361Y-252763D01*
G01X-702446D02*
X-693276Y-235263D01*
G01X-702446D02*
X-693276Y-252763D01*
G01X-658494D02*
X-667228D01*
Y-235263D01*
X-658494D01*
G01X-661988Y-243721D02*
X-667228D01*
G01X-649946Y-252763D02*
X-640776Y-235263D01*
G01X-649946D02*
X-640776Y-252763D01*
G01X-632228D02*
Y-235263D01*
X-626988D01*
X-625241Y-236138D01*
X-623931Y-238180D01*
X-623494Y-240513D01*
X-623931Y-242846D01*
X-625023Y-244596D01*
X-626988Y-245472D01*
X-632228D01*
G01X-615820Y-252763D02*
X-610361Y-235263D01*
X-604902Y-252763D01*
G01X-606868Y-246638D02*
X-613855D01*
G01X-597883Y-252763D02*
Y-235263D01*
X-587839Y-252763D01*
Y-235263D01*
G01X-580164Y-252763D02*
Y-235263D01*
X-575798D01*
X-574051Y-236138D01*
X-572741Y-237305D01*
X-571649Y-239054D01*
X-570776Y-241097D01*
X-570558Y-244013D01*
X-570776Y-246930D01*
X-571649Y-248972D01*
X-572741Y-250722D01*
X-574051Y-251888D01*
X-575798Y-252763D01*
X-580164D01*
G01X-553494D02*
X-562228D01*
Y-235263D01*
X-553494D01*
G01X-556988Y-243721D02*
X-562228D01*
G01X-544728Y-252763D02*
Y-235263D01*
X-539269D01*
X-537523Y-236138D01*
X-536431Y-237305D01*
X-535994Y-239638D01*
X-536431Y-241972D01*
X-537741Y-243430D01*
X-539269Y-244305D01*
X-544728D01*
G01X-539269D02*
X-535994Y-252763D01*
G01X-503615Y-243430D02*
X-502741Y-242555D01*
X-502086Y-241097D01*
X-501649Y-239054D01*
X-502086Y-237305D01*
X-502959Y-236138D01*
X-504488Y-235263D01*
X-510383D01*
Y-252763D01*
X-503178D01*
X-501649Y-251597D01*
X-500776Y-249846D01*
X-500339Y-247805D01*
X-500776Y-245763D01*
X-502086Y-244013D01*
X-503615Y-243430D01*
X-510383D01*
G01X-487861Y-252763D02*
X-489608Y-252471D01*
X-491136Y-251305D01*
X-492446Y-249555D01*
X-493320Y-247513D01*
X-493756Y-245180D01*
Y-242846D01*
X-493320Y-240513D01*
X-492446Y-238471D01*
X-491136Y-236722D01*
X-489608Y-235555D01*
X-487861Y-235263D01*
X-486115Y-235555D01*
X-484586Y-236722D01*
X-483276Y-238471D01*
X-482402Y-240513D01*
X-481966Y-242846D01*
Y-245180D01*
X-482402Y-247513D01*
X-483276Y-249555D01*
X-484586Y-251305D01*
X-486115Y-252471D01*
X-487861Y-252763D01*
G01X-475820D02*
X-470361Y-235263D01*
X-464902Y-252763D01*
G01X-466868Y-246638D02*
X-473855D01*
G01X-457228Y-252763D02*
Y-235263D01*
X-451769D01*
X-450023Y-236138D01*
X-448931Y-237305D01*
X-448494Y-239638D01*
X-448931Y-241972D01*
X-450241Y-243430D01*
X-451769Y-244305D01*
X-457228D01*
G01X-451769D02*
X-448494Y-252763D01*
G01X-440164D02*
Y-235263D01*
X-435798D01*
X-434051Y-236138D01*
X-432741Y-237305D01*
X-431649Y-239054D01*
X-430776Y-241097D01*
X-430558Y-244013D01*
X-430776Y-246930D01*
X-431649Y-248972D01*
X-432741Y-250722D01*
X-434051Y-251888D01*
X-435798Y-252763D01*
X-440164D01*
G01X-633538Y-207763D02*
Y-190263D01*
X-627861Y-204846D01*
X-622184Y-190263D01*
Y-207763D01*
G01X-610361D02*
X-611671Y-207471D01*
X-612981Y-206305D01*
X-613855Y-204263D01*
X-614291Y-201930D01*
X-613855Y-199596D01*
X-612981Y-197555D01*
X-611671Y-196388D01*
X-610361Y-196097D01*
X-609051Y-196388D01*
X-607741Y-197555D01*
X-606868Y-199596D01*
X-606649Y-201930D01*
X-606868Y-204263D01*
X-607741Y-206305D01*
X-609051Y-207471D01*
X-610361Y-207763D01*
G01X-588931Y-190263D02*
Y-207763D01*
G01Y-205139D02*
X-589804Y-206597D01*
X-591115Y-207471D01*
X-592643Y-207763D01*
X-594389Y-207180D01*
X-595699Y-205722D01*
X-596573Y-203972D01*
X-596791Y-201930D01*
X-596573Y-199888D01*
X-595699Y-198138D01*
X-594389Y-196680D01*
X-592643Y-196097D01*
X-591115Y-196388D01*
X-590023Y-196972D01*
X-588931Y-198138D01*
G01X-578636Y-199888D02*
X-571649D01*
X-572304Y-197846D01*
X-573396Y-196680D01*
X-574924Y-196097D01*
X-576453Y-196388D01*
X-577763Y-197263D01*
X-578636Y-199305D01*
X-579073Y-201055D01*
Y-202805D01*
X-578636Y-204555D01*
X-577544Y-206305D01*
X-576234Y-207471D01*
X-574706Y-207763D01*
X-573178Y-207180D01*
X-571649Y-205430D01*
G01X-557861Y-207763D02*
Y-190263D01*
G01X-380161Y-252763D02*
Y-235263D01*
X-382781Y-238763D01*
G01Y-252763D02*
X-377541D01*
G01X-366809Y-238180D02*
X-365499Y-236430D01*
X-363971Y-235555D01*
X-362224Y-235263D01*
X-360041Y-235846D01*
X-358513Y-237305D01*
X-358076Y-239054D01*
X-358294Y-240805D01*
X-359168Y-242263D01*
X-363534Y-245180D01*
X-365499Y-247221D01*
X-366809Y-250139D01*
X-367246Y-252763D01*
X-358076D01*
G01X-345161Y-235263D02*
X-346908Y-235846D01*
X-348218Y-237305D01*
X-349091Y-239054D01*
X-349746Y-241388D01*
X-349964Y-244013D01*
X-349746Y-246638D01*
X-349091Y-248972D01*
X-348218Y-250722D01*
X-346908Y-252180D01*
X-345161Y-252763D01*
X-343415Y-252180D01*
X-342104Y-250722D01*
X-341231Y-248972D01*
X-340576Y-246638D01*
X-340358Y-244013D01*
X-340576Y-241388D01*
X-341231Y-239054D01*
X-342104Y-237305D01*
X-343415Y-235846D01*
X-345161Y-235263D01*
G01X-327661D02*
X-329408Y-235846D01*
X-330718Y-237305D01*
X-331591Y-239054D01*
X-332246Y-241388D01*
X-332464Y-244013D01*
X-332246Y-246638D01*
X-331591Y-248972D01*
X-330718Y-250722D01*
X-329408Y-252180D01*
X-327661Y-252763D01*
X-325915Y-252180D01*
X-324604Y-250722D01*
X-323731Y-248972D01*
X-323076Y-246638D01*
X-322858Y-244013D01*
X-323076Y-241388D01*
X-323731Y-239054D01*
X-324604Y-237305D01*
X-325915Y-235846D01*
X-327661Y-235263D01*
G01X-307541Y-252763D02*
Y-235263D01*
X-315620Y-247805D01*
X-304702D01*
G01X-393278Y-207763D02*
Y-190263D01*
X-388038D01*
X-386291Y-191138D01*
X-384981Y-193180D01*
X-384544Y-195513D01*
X-384981Y-197846D01*
X-386073Y-199596D01*
X-388038Y-200472D01*
X-393278D01*
G01X-366608Y-191722D02*
X-367918Y-190846D01*
X-369446Y-190263D01*
X-371193D01*
X-373158Y-191138D01*
X-374686Y-192596D01*
X-375778Y-194347D01*
X-376651Y-197263D01*
X-376870Y-199888D01*
X-376433Y-202513D01*
X-375778Y-204263D01*
X-374468Y-206013D01*
X-372939Y-207180D01*
X-371411Y-207763D01*
X-369883D01*
X-368354Y-207180D01*
X-367044Y-206305D01*
X-365952Y-205139D01*
G01X-352165Y-198430D02*
X-351291Y-197555D01*
X-350636Y-196097D01*
X-350199Y-194054D01*
X-350636Y-192305D01*
X-351509Y-191138D01*
X-353038Y-190263D01*
X-358933D01*
Y-207763D01*
X-351728D01*
X-350199Y-206597D01*
X-349326Y-204846D01*
X-348889Y-202805D01*
X-349326Y-200763D01*
X-350636Y-199013D01*
X-352165Y-198430D01*
X-358933D01*
G01X-342961Y-213596D02*
X-329861D01*
G01X-323933Y-207763D02*
Y-190263D01*
X-313889Y-207763D01*
Y-190263D01*
G01X-301411Y-207763D02*
X-303158Y-207471D01*
X-304686Y-206305D01*
X-305996Y-204555D01*
X-306870Y-202513D01*
X-307306Y-200180D01*
Y-197846D01*
X-306870Y-195513D01*
X-305996Y-193471D01*
X-304686Y-191722D01*
X-303158Y-190555D01*
X-301411Y-190263D01*
X-299665Y-190555D01*
X-298136Y-191722D01*
X-296826Y-193471D01*
X-295952Y-195513D01*
X-295516Y-197846D01*
Y-200180D01*
X-295952Y-202513D01*
X-296826Y-204555D01*
X-298136Y-206305D01*
X-299665Y-207471D01*
X-301411Y-207763D01*
G01X-218861Y-252763D02*
Y-235263D01*
X-221481Y-238763D01*
G01Y-252763D02*
X-216241D01*
G01X-250570Y-190263D02*
X-245111Y-207763D01*
X-239652Y-190263D01*
G01X-223244Y-207763D02*
X-231978D01*
Y-190263D01*
X-223244D01*
G01X-226738Y-198721D02*
X-231978D01*
G01X-214478Y-207763D02*
Y-190263D01*
X-209019D01*
X-207273Y-191138D01*
X-206181Y-192305D01*
X-205744Y-194638D01*
X-206181Y-196972D01*
X-207491Y-198430D01*
X-209019Y-199305D01*
X-214478D01*
G01X-209019D02*
X-205744Y-207763D01*
G01X-192611Y-208346D02*
X-193048Y-208055D01*
Y-207471D01*
X-192611Y-207180D01*
X-192174Y-207471D01*
Y-208055D01*
X-192611Y-208346D01*
G01X-64544Y-235263D02*
Y-252763D01*
X-73278D01*
G01X-86411D02*
X-87939Y-252471D01*
X-89686Y-251597D01*
X-90778Y-250139D01*
X-91214Y-248096D01*
X-90778Y-246055D01*
X-89468Y-244305D01*
X-87503Y-243430D01*
X-85319D01*
X-84009Y-242846D01*
X-82917Y-241388D01*
X-82481Y-239347D01*
X-83136Y-237305D01*
X-84664Y-235846D01*
X-86411Y-235263D01*
X-88157Y-235846D01*
X-89686Y-237305D01*
X-90341Y-239347D01*
X-89904Y-241388D01*
X-88813Y-242846D01*
X-87503Y-243430D01*
X-85319D01*
X-83354Y-244305D01*
X-82044Y-246055D01*
X-81608Y-248096D01*
X-82044Y-250139D01*
X-83136Y-251597D01*
X-84883Y-252471D01*
X-86411Y-252763D01*
G01X-125778Y-190263D02*
Y-207763D01*
X-117044D01*
G01X-99981D02*
Y-196097D01*
G01Y-198138D02*
X-100854Y-196972D01*
X-102165Y-196388D01*
X-103693Y-196097D01*
X-105221Y-196680D01*
X-106531Y-197846D01*
X-107405Y-199596D01*
X-107841Y-201930D01*
X-107405Y-204263D01*
X-106531Y-206013D01*
X-105221Y-207180D01*
X-103693Y-207763D01*
X-102165Y-207471D01*
X-100854Y-206597D01*
X-99981Y-205430D01*
G01X-90996Y-213013D02*
X-89686Y-213596D01*
X-87939Y-213013D01*
X-86848Y-211847D01*
X-85974Y-210388D01*
X-84665Y-205722D01*
X-81826Y-196097D01*
G01X-88813D02*
X-84665Y-205722D01*
G01X-72186Y-199888D02*
X-65199D01*
X-65854Y-197846D01*
X-66946Y-196680D01*
X-68474Y-196097D01*
X-70003Y-196388D01*
X-71313Y-197263D01*
X-72186Y-199305D01*
X-72623Y-201055D01*
Y-202805D01*
X-72186Y-204555D01*
X-71094Y-206305D01*
X-69784Y-207471D01*
X-68256Y-207763D01*
X-66728Y-207180D01*
X-65199Y-205430D01*
G01X-54468Y-207763D02*
Y-196097D01*
G01Y-198430D02*
X-53376Y-197263D01*
X-52284Y-196388D01*
X-50756Y-196097D01*
X-49665Y-196388D01*
X-48354Y-197263D01*
G01X-37186Y-205722D02*
X-36094Y-206888D01*
X-34566Y-207763D01*
X-33256D01*
X-31946Y-207180D01*
X-31073Y-206305D01*
X-30636Y-205139D01*
X-30854Y-203388D01*
X-31728Y-202513D01*
X-35658Y-200763D01*
X-36531Y-198721D01*
X-36094Y-197263D01*
X-35221Y-196388D01*
X-33911Y-196097D01*
X-32601Y-196388D01*
X-31291Y-197263D01*
G01X51772Y-235263D02*
Y-252763D01*
X60506D01*
G01X68836Y-235263D02*
Y-247805D01*
X69709Y-250430D01*
X71456Y-252180D01*
X73639Y-252763D01*
X75822Y-252180D01*
X77569Y-250430D01*
X78442Y-247805D01*
Y-235263D01*
G01X95942Y-236722D02*
X94632Y-235846D01*
X93104Y-235263D01*
X91357D01*
X89392Y-236138D01*
X87864Y-237596D01*
X86772Y-239347D01*
X85899Y-242263D01*
X85680Y-244888D01*
X86117Y-247513D01*
X86772Y-249263D01*
X88082Y-251013D01*
X89611Y-252180D01*
X91139Y-252763D01*
X92667D01*
X94196Y-252180D01*
X95506Y-251305D01*
X96598Y-250139D01*
G01X103836Y-252763D02*
Y-235263D01*
G01X112132D02*
X103836Y-246055D01*
G01X113442Y-252763D02*
X107547Y-241097D01*
G01X126139Y-252763D02*
Y-244888D01*
X121772Y-235263D01*
G01X130506D02*
X126139Y-244888D01*
G01X25086Y-207763D02*
Y-190263D01*
X29452D01*
X31199Y-191138D01*
X32509Y-192305D01*
X33601Y-194054D01*
X34474Y-196097D01*
X34692Y-199013D01*
X34474Y-201930D01*
X33601Y-203972D01*
X32509Y-205722D01*
X31199Y-206888D01*
X29452Y-207763D01*
X25086D01*
G01X44114Y-199888D02*
X51101D01*
X50446Y-197846D01*
X49354Y-196680D01*
X47826Y-196097D01*
X46297Y-196388D01*
X44987Y-197263D01*
X44114Y-199305D01*
X43677Y-201055D01*
Y-202805D01*
X44114Y-204555D01*
X45206Y-206305D01*
X46516Y-207471D01*
X48044Y-207763D01*
X49572Y-207180D01*
X51101Y-205430D01*
G01X61614Y-205722D02*
X62706Y-206888D01*
X64234Y-207763D01*
X65544D01*
X66854Y-207180D01*
X67727Y-206305D01*
X68164Y-205139D01*
X67946Y-203388D01*
X67072Y-202513D01*
X63142Y-200763D01*
X62269Y-198721D01*
X62706Y-197263D01*
X63579Y-196388D01*
X64889Y-196097D01*
X66199Y-196388D01*
X67509Y-197263D01*
G01X82389Y-196097D02*
Y-207763D01*
G01Y-191430D02*
X81952Y-191138D01*
Y-190555D01*
X82389Y-190263D01*
X82826Y-190555D01*
Y-191138D01*
X82389Y-191430D01*
G01X96832Y-212138D02*
X98361Y-213305D01*
X100107Y-213596D01*
X101635Y-213305D01*
X102946Y-211847D01*
X103819Y-209805D01*
Y-196097D01*
G01Y-198430D02*
X102946Y-197263D01*
X101635Y-196388D01*
X100107Y-196097D01*
X98361Y-196680D01*
X97269Y-197846D01*
X96395Y-199888D01*
X95959Y-201930D01*
X96177Y-203680D01*
X97051Y-205722D01*
X98361Y-207180D01*
X100107Y-207763D01*
X101417Y-207471D01*
X102946Y-206305D01*
X103819Y-205139D01*
G01X113677Y-207763D02*
Y-196097D01*
G01Y-199013D02*
X114551Y-197555D01*
X115861Y-196388D01*
X117607Y-196097D01*
X119135Y-196388D01*
X120446Y-197555D01*
X121101Y-199596D01*
Y-207763D01*
G01X131614Y-199888D02*
X138601D01*
X137946Y-197846D01*
X136854Y-196680D01*
X135326Y-196097D01*
X133797Y-196388D01*
X132487Y-197263D01*
X131614Y-199305D01*
X131177Y-201055D01*
Y-202805D01*
X131614Y-204555D01*
X132706Y-206305D01*
X134016Y-207471D01*
X135544Y-207763D01*
X137072Y-207180D01*
X138601Y-205430D01*
G01X149332Y-207763D02*
Y-196097D01*
G01Y-198430D02*
X150424Y-197263D01*
X151516Y-196388D01*
X153044Y-196097D01*
X154135Y-196388D01*
X155446Y-197263D01*
G01X196089Y-252763D02*
Y-235263D01*
X193469Y-238763D01*
G01Y-252763D02*
X198709D01*
G01X213589Y-235263D02*
X211842Y-235846D01*
X210532Y-237305D01*
X209659Y-239054D01*
X209004Y-241388D01*
X208786Y-244013D01*
X209004Y-246638D01*
X209659Y-248972D01*
X210532Y-250722D01*
X211842Y-252180D01*
X213589Y-252763D01*
X215335Y-252180D01*
X216646Y-250722D01*
X217519Y-248972D01*
X218174Y-246638D01*
X218392Y-244013D01*
X218174Y-241388D01*
X217519Y-239054D01*
X216646Y-237305D01*
X215335Y-235846D01*
X213589Y-235263D01*
G01X227159Y-253346D02*
X235019Y-235263D01*
G01X248589Y-252763D02*
Y-235263D01*
X245969Y-238763D01*
G01Y-252763D02*
X251209D01*
G01X261941Y-245472D02*
X263469Y-243430D01*
X264779Y-242263D01*
X266526Y-241680D01*
X268054Y-242263D01*
X269146Y-243430D01*
X270019Y-245180D01*
X270237Y-247221D01*
X270019Y-248972D01*
X269146Y-250722D01*
X267835Y-252180D01*
X266307Y-252763D01*
X264561Y-252180D01*
X263032Y-250430D01*
X262159Y-247805D01*
X261941Y-244888D01*
X262377Y-241097D01*
X263032Y-239054D01*
X264124Y-237013D01*
X265652Y-235555D01*
X267181Y-235263D01*
X268709Y-235846D01*
X269801Y-237305D01*
G01X279659Y-253346D02*
X287519Y-235263D01*
G01X296941Y-238180D02*
X298251Y-236430D01*
X299779Y-235555D01*
X301526Y-235263D01*
X303709Y-235846D01*
X305237Y-237305D01*
X305674Y-239054D01*
X305456Y-240805D01*
X304582Y-242263D01*
X300216Y-245180D01*
X298251Y-247221D01*
X296941Y-250139D01*
X296504Y-252763D01*
X305674D01*
G01X318589Y-235263D02*
X316842Y-235846D01*
X315532Y-237305D01*
X314659Y-239054D01*
X314004Y-241388D01*
X313786Y-244013D01*
X314004Y-246638D01*
X314659Y-248972D01*
X315532Y-250722D01*
X316842Y-252180D01*
X318589Y-252763D01*
X320335Y-252180D01*
X321646Y-250722D01*
X322519Y-248972D01*
X323174Y-246638D01*
X323392Y-244013D01*
X323174Y-241388D01*
X322519Y-239054D01*
X321646Y-237305D01*
X320335Y-235846D01*
X318589Y-235263D01*
G01X336089Y-252763D02*
Y-235263D01*
X333469Y-238763D01*
G01Y-252763D02*
X338709D01*
G01X349441Y-238180D02*
X350751Y-236430D01*
X352279Y-235555D01*
X354026Y-235263D01*
X356209Y-235846D01*
X357737Y-237305D01*
X358174Y-239054D01*
X357956Y-240805D01*
X357082Y-242263D01*
X352716Y-245180D01*
X350751Y-247221D01*
X349441Y-250139D01*
X349004Y-252763D01*
X358174D01*
G01X243786Y-207763D02*
Y-190263D01*
X248152D01*
X249899Y-191138D01*
X251209Y-192305D01*
X252301Y-194054D01*
X253174Y-196097D01*
X253392Y-199013D01*
X253174Y-201930D01*
X252301Y-203972D01*
X251209Y-205722D01*
X249899Y-206888D01*
X248152Y-207763D01*
X243786D01*
G01X270019D02*
Y-196097D01*
G01Y-198138D02*
X269146Y-196972D01*
X267835Y-196388D01*
X266307Y-196097D01*
X264779Y-196680D01*
X263469Y-197846D01*
X262595Y-199596D01*
X262159Y-201930D01*
X262595Y-204263D01*
X263469Y-206013D01*
X264779Y-207180D01*
X266307Y-207763D01*
X267835Y-207471D01*
X269146Y-206597D01*
X270019Y-205430D01*
G01X283589Y-190263D02*
Y-207763D01*
G01X280532Y-196097D02*
X286646D01*
G01X297814Y-199888D02*
X304801D01*
X304146Y-197846D01*
X303054Y-196680D01*
X301526Y-196097D01*
X299997Y-196388D01*
X298687Y-197263D01*
X297814Y-199305D01*
X297377Y-201055D01*
Y-202805D01*
X297814Y-204555D01*
X298906Y-206305D01*
X300216Y-207471D01*
X301744Y-207763D01*
X303272Y-207180D01*
X304801Y-205430D01*
G01X223600Y456200D02*
X222403Y457397D01*
X219728D01*
G01X226000Y458700D02*
X224700Y460000D01*
Y462200D01*
G54D19*
X55700Y87600D03*
X59274Y87603D03*
X35230Y306738D03*
X134663Y456583D03*
X681300Y510400D03*
X648500Y536800D03*
X677800Y510400D03*
X725784Y554587D03*
G54D55*
X419225Y453324D03*
G54D28*
X65830Y181464D03*
X58080D03*
X61955Y188964D03*
X56759Y199321D03*
X49009D03*
X52884Y206821D03*
G54D46*
X60403Y524823D03*
Y517073D03*
X52903Y520948D03*
X57065Y544023D03*
Y536273D03*
X49565Y540148D03*
G54D37*
X53547Y322486D03*
Y302486D03*
X182681Y580832D03*
Y560832D03*
G54D64*
X781514Y334665D03*
Y338605D03*
Y342540D03*
Y346480D03*
Y350415D03*
Y354350D03*
Y358290D03*
Y362225D03*
Y366165D03*
Y370100D03*
Y381910D03*
Y385850D03*
Y389785D03*
Y393720D03*
Y397660D03*
Y401595D03*
Y405535D03*
Y409470D03*
Y413405D03*
Y417345D03*
Y421280D03*
Y425220D03*
Y429155D03*
Y433090D03*
Y437030D03*
Y440965D03*
Y444905D03*
Y448840D03*
Y452775D03*
Y456715D03*
Y460650D03*
Y464590D03*
Y468525D03*
Y472460D03*
Y476400D03*
Y480335D03*
Y484275D03*
Y488210D03*
Y492145D03*
Y496085D03*
Y500020D03*
Y503960D03*
Y507895D03*
Y511830D03*
Y515770D03*
Y519705D03*
Y523645D03*
Y527580D03*
Y531515D03*
Y535455D03*
Y539390D03*
Y543330D03*
Y547265D03*
Y551200D03*
Y555140D03*
Y559075D03*
Y563015D03*
Y566950D03*
Y570885D03*
Y574825D03*
Y578760D03*
Y582700D03*
Y586635D03*
Y590575D03*
Y594510D03*
Y598445D03*
Y602385D03*
Y606320D03*
Y610260D03*
Y614195D03*
Y618130D03*
Y622070D03*
Y626005D03*
Y629945D03*
Y633880D03*
Y637815D03*
Y641755D03*
Y645690D03*
Y649630D03*
Y653565D03*
Y657500D03*
Y744114D03*
Y748054D03*
Y751989D03*
Y755929D03*
Y759864D03*
Y763799D03*
Y767739D03*
Y771674D03*
Y775614D03*
Y779549D03*
Y791359D03*
Y795299D03*
Y799234D03*
Y803169D03*
Y807109D03*
Y811044D03*
Y814984D03*
G54D65*
G01X35230Y306788D02*
X33700Y305258D01*
Y305057D01*
X32984Y304341D01*
Y299567D01*
G01X21876Y282289D02*
X22854Y283267D01*
X25304D01*
G01X131150Y228600D02*
X131538Y228988D01*
Y236823D01*
X131478Y236883D01*
G01X120713Y228683D02*
X121243Y229213D01*
Y236883D01*
G01X94313Y228783D02*
X93513Y229583D01*
Y229903D01*
X93093Y230323D01*
Y236883D01*
G01X106513Y228783D02*
Y230651D01*
X105948Y231216D01*
Y236823D01*
X105888Y236883D01*
G01X132013Y305603D02*
X131478Y305068D01*
Y297283D01*
G01X168010Y267909D02*
X165904Y265803D01*
X161963D01*
G01X150513Y228783D02*
Y231000D01*
X149393Y232120D01*
Y236883D01*
G01X152663Y267791D02*
X152723D01*
X153295Y268363D01*
X161963D01*
G01X400934Y453986D02*
X402831Y455883D01*
X409482D01*
G01X400934Y453986D02*
X401596Y453324D01*
X409482D01*
G01X428968Y450765D02*
X433744D01*
X435016Y449493D01*
G01X421273Y439381D02*
Y439468D01*
X421784Y439979D01*
Y443581D01*
G01X434994Y453811D02*
X434507Y453324D01*
X428968D01*
G01X434994Y453811D02*
X434294Y454511D01*
X433833D01*
X432461Y455883D01*
X428968D01*
G01X677815Y493833D02*
Y490733D01*
X680225Y488323D01*
Y486151D01*
G01X701858Y454209D02*
X707573D01*
X708059Y453723D01*
G01X679809Y478423D02*
Y485367D01*
X680409Y485967D01*
X680225Y486151D01*
G01X687858Y466020D02*
X684718D01*
X682915Y467823D01*
G01X679809Y478423D02*
X682102Y476130D01*
X684259D01*
G01X707700Y476500D02*
X707063Y475863D01*
X701858D01*
G01X682915Y467823D02*
X682469Y467377D01*
X679415D01*
G01X684259Y476130D02*
X684526Y475863D01*
X687858D01*
G01X681859Y453623D02*
X682445Y454209D01*
X687858D01*
G01X679415Y463877D02*
X679589Y464051D01*
X687858D01*
G01X679415Y467377D02*
Y463877D01*
G01X712102Y537033D02*
Y542133D01*
G54D29*
X47940Y212898D03*
G54D38*
X32984Y299567D03*
X30424D03*
X27864D03*
X25304D03*
Y283267D03*
X27864D03*
X30424D03*
X32984D03*
X687385Y518741D03*
X689945D03*
X692505D03*
X695065D03*
Y535041D03*
X692505D03*
X689945D03*
X687385D03*
X712102Y553333D03*
Y537033D03*
X654710Y540455D03*
X657270D03*
X659830D03*
X662390D03*
Y556755D03*
X659830D03*
X657270D03*
X654710D03*
X719782Y553333D03*
X717222D03*
X714662D03*
Y537033D03*
X717222D03*
X719782D03*
G54D56*
X414107Y443581D03*
X416666D03*
X419225D03*
X421784D03*
X424343D03*
Y463067D03*
X421784D03*
X419225D03*
X416666D03*
X414107D03*
G54D47*
X62000Y609872D03*
Y605972D03*
X62100Y600272D03*
Y596372D03*
Y576887D03*
Y572987D03*
X62200Y567387D03*
Y563487D03*
X62651Y694403D03*
Y690503D03*
Y684703D03*
Y680803D03*
X61600Y728513D03*
Y724613D03*
X61700Y718613D03*
Y714713D03*
X131100Y228600D03*
X90763Y228783D03*
X90819Y305456D03*
X121263Y305503D03*
X131963Y305603D03*
X106805Y413570D03*
X114863Y421283D03*
X120963Y441583D03*
X121763Y449983D03*
X113363Y441583D03*
X109463Y434383D03*
X136163Y441583D03*
X129663Y449183D03*
X119263Y433683D03*
X126983Y434871D03*
Y431371D03*
X129663Y452683D03*
X171696Y269694D03*
X168269Y432425D03*
X157063Y440683D03*
X150640Y837095D03*
X150751Y832781D03*
Y828981D03*
X152236Y817740D03*
Y814140D03*
X151488Y853750D03*
X151561Y850210D03*
X150440Y840895D03*
X707930Y464221D03*
X708009Y453723D03*
X653700Y533400D03*
G54D66*
G01X57200Y175300D02*
Y175700D01*
X51926Y180974D01*
X50244D01*
G54D39*
X75876Y307064D03*
Y314664D03*
X50799Y499966D03*
Y492366D03*
X400934Y446386D03*
Y453986D03*
X393110Y446429D03*
Y454029D03*
G54D57*
X428968Y448206D03*
Y450765D03*
Y453324D03*
Y455883D03*
Y458442D03*
X409482D03*
Y455883D03*
Y453324D03*
Y450765D03*
Y448206D03*
G54D48*
X65600Y609872D03*
Y605972D03*
X65700Y600272D03*
Y596372D03*
Y576887D03*
Y572987D03*
X65800Y567387D03*
Y563487D03*
X66251Y694403D03*
Y690503D03*
Y684703D03*
Y680803D03*
X65200Y728513D03*
Y724613D03*
X65300Y718613D03*
Y714713D03*
X134700Y228600D03*
X94363Y228783D03*
X94419Y305456D03*
X124863Y305503D03*
X135563Y305603D03*
X110405Y413570D03*
X118463Y421283D03*
X124563Y441583D03*
X125363Y449983D03*
X116963Y441583D03*
X113063Y434383D03*
X139763Y441583D03*
X133263Y449183D03*
X122863Y433683D03*
X130583Y434871D03*
Y431371D03*
X133263Y452683D03*
X175296Y269694D03*
X171869Y432425D03*
X160663Y440683D03*
X154240Y837095D03*
X154351Y832781D03*
Y828981D03*
X155836Y817740D03*
Y814140D03*
X155088Y853750D03*
X155161Y850210D03*
X154040Y840895D03*
X711530Y464221D03*
X711609Y453723D03*
X657300Y533400D03*
G54D67*
G01X251687Y98033D02*
X208040Y141680D01*
X160311D01*
G01X667979Y486293D02*
X672483D01*
X672625Y486151D01*
G54D58*
X419626Y481966D03*
X427526D03*
G54D49*
X82858Y236883D03*
X85418D03*
X87973D03*
X90533D03*
X93093D03*
X95653D03*
X98213D03*
X100768D03*
X103328D03*
X105888D03*
X108448D03*
X111008D03*
X113563D03*
X116123D03*
X118683D03*
X146833D03*
X144273D03*
X141713D03*
X139158D03*
X136598D03*
X134038D03*
X131478D03*
X128918D03*
X126363D03*
X123803D03*
X121243D03*
X146833Y297283D03*
X144273D03*
X141713D03*
X139158D03*
X136598D03*
X134038D03*
X131478D03*
X128918D03*
X126363D03*
X123803D03*
X121243D03*
X82858D03*
X85418D03*
X87973D03*
X90533D03*
X93093D03*
X95653D03*
X98213D03*
X100768D03*
X103328D03*
X105888D03*
X108448D03*
X111008D03*
X113563D03*
X116123D03*
X118683D03*
X157068Y236883D03*
X154508D03*
X151953D03*
X149393D03*
X157068Y297283D03*
X154508D03*
X151953D03*
X149393D03*
G54D68*
G01X63444Y266161D02*
X65216Y267933D01*
X70356D01*
X70925Y268502D01*
X73077D01*
X73216Y268363D01*
X77963D01*
G01X60102Y263180D02*
Y263867D01*
X62396Y266161D01*
X63444D01*
G01X72001Y265901D02*
X72099Y265803D01*
X77963D01*
G01X63444Y262661D02*
X68761D01*
X72001Y265901D01*
G01X110013Y228783D02*
Y230687D01*
X108448Y232252D01*
Y236883D01*
G01X90813Y228783D02*
X90533Y229063D01*
Y236883D01*
G01X117213Y228683D02*
X116123Y229773D01*
Y236883D01*
G01X134650Y228600D02*
X134038Y229212D01*
Y236883D01*
G01X147013Y228783D02*
X146833Y228963D01*
Y236883D01*
G01X150713Y305503D02*
Y303313D01*
X149393Y301993D01*
Y297283D01*
G01X90869Y305456D02*
X90533Y305120D01*
Y297283D01*
G01X109686Y306270D02*
X108536Y305120D01*
Y304572D01*
X108448Y304484D01*
Y297283D01*
G01X117213Y306003D02*
X120813D01*
X121313Y305503D01*
G01X118683Y297283D02*
Y304533D01*
X117213Y306003D01*
G01X146833Y297283D02*
Y305123D01*
X147213Y305503D01*
G01X106419Y310245D02*
X106186Y310012D01*
Y306270D01*
G01X135513Y305603D02*
X135212Y305302D01*
Y304842D01*
X134038Y303668D01*
Y297283D01*
G01X124813Y305503D02*
X124113Y304803D01*
Y304342D01*
X123803Y304032D01*
Y297283D01*
G01X106186Y306270D02*
X105888Y305972D01*
Y297283D01*
G01X94369Y305456D02*
Y304287D01*
X93093Y303011D01*
Y297283D01*
G01X654710Y540455D02*
Y534963D01*
X654350Y534603D01*
Y534000D01*
X653750Y533400D01*
G01X681300Y510450D02*
X682250D01*
X687385Y515585D01*
Y518741D01*
G01X662390Y556755D02*
X665344D01*
X665499Y556600D01*
G01X701500Y535000D02*
X695106D01*
X695065Y535041D01*
G54D59*
X384609Y445387D03*
Y453287D03*
G54D69*
G01X90662Y461604D02*
X91208Y462150D01*
X94500D01*
G01X681300Y510450D02*
X677800D01*
G01X674375Y509826D02*
X674999Y510450D01*
X677800D01*
G01X725784Y554637D02*
X722437D01*
X721133Y553333D01*
X719782D01*
M02*
